FILE_TYPE = MACRO_DRAWING;
SET COLOR_WIRE YELLOW;
SET COLOR_PROP ORANGE;
SET COLOR_DOT WHITE;
SET COLOR_ARC YELLOW;
SET COLOR_BODY GREEN;
SET COLOR_NOTE PURPLE;
SET PROP_DISPLAY VALUE;
SET PAGE_NUMBER P319;
FORCEADD OFFPAGE..1
(-3325 -725);
FORCEPROP 2 LAST $XR0 353 
J 0
(-3607 -725);
DISPLAY 0.638298 (-3607 -725);
PAINT MONO (-3607 -725);
FORCEPROP 2 LAST CDS_LIB standard
J 0
(-3325 -725);
DISPLAY INVISIBLE (-3325 -725);
FORCEPROP 1 LAST OFFPAGE TRUE
J 0
(-3000 -850);
DISPLAY 0.872340 (-3000 -850);
PAINT AQUA (-3000 -850);
DISPLAY INVISIBLE (-3000 -850);
FORCEPROP 1 LAST COMMENT_BODY TRUE
J 0
(-3200 -825);
DISPLAY 0.872340 (-3200 -825);
PAINT GREEN (-3200 -825);
DISPLAY INVISIBLE (-3200 -825);
FORCEPROP 2 LAST PATH I1
J 0
(-3575 -675);
DISPLAY 0.680851 (-3575 -675);
DISPLAY INVISIBLE (-3575 -675);
FORCEADD OFFPAGE..3
R 2
(-3325 -125);
FORCEPROP 2 LAST $XR0 249 
J 0
(-3605 -125);
DISPLAY 0.638298 (-3605 -125);
PAINT MONO (-3605 -125);
FORCEPROP 2 LAST CDS_LIB standard
J 0
(-3325 -125);
DISPLAY INVISIBLE (-3325 -125);
FORCEPROP 1 LAST OFFPAGE TRUE
J 2
(-3650 -250);
DISPLAY 0.872340 (-3650 -250);
DISPLAY INVISIBLE (-3650 -250);
FORCEPROP 1 LAST COMMENT_BODY TRUE
J 2
(-3275 -225);
DISPLAY 0.872340 (-3275 -225);
PAINT GREEN (-3275 -225);
DISPLAY INVISIBLE (-3275 -225);
FORCEPROP 2 LAST PATH I10
J 0
(-3600 -75);
DISPLAY 0.680851 (-3600 -75);
DISPLAY INVISIBLE (-3600 -75);
FORCEADD OFFPAGE..1
(-3325 125);
FORCEPROP 2 LAST $XR0 353 
J 0
(-3607 125);
DISPLAY 0.638298 (-3607 125);
PAINT MONO (-3607 125);
FORCEPROP 2 LAST CDS_LIB standard
J 0
(-3325 125);
DISPLAY INVISIBLE (-3325 125);
FORCEPROP 1 LAST OFFPAGE TRUE
J 0
(-3000 0);
DISPLAY 0.872340 (-3000 0);
PAINT AQUA (-3000 0);
DISPLAY INVISIBLE (-3000 0);
FORCEPROP 1 LAST COMMENT_BODY TRUE
J 0
(-3200 25);
DISPLAY 0.872340 (-3200 25);
PAINT GREEN (-3200 25);
DISPLAY INVISIBLE (-3200 25);
FORCEPROP 2 LAST PATH I11
J 0
(-3575 175);
DISPLAY 0.680851 (-3575 175);
DISPLAY INVISIBLE (-3575 175);
FORCEADD OFFPAGE..1
(-3325 275);
FORCEPROP 2 LAST $XR0 342 
J 0
(-3607 275);
DISPLAY 0.638298 (-3607 275);
PAINT MONO (-3607 275);
FORCEPROP 2 LAST CDS_LIB standard
J 0
(-3325 275);
DISPLAY INVISIBLE (-3325 275);
FORCEPROP 1 LAST OFFPAGE TRUE
J 0
(-3000 150);
DISPLAY 0.872340 (-3000 150);
PAINT AQUA (-3000 150);
DISPLAY INVISIBLE (-3000 150);
FORCEPROP 1 LAST COMMENT_BODY TRUE
J 0
(-3200 175);
DISPLAY 0.872340 (-3200 175);
PAINT GREEN (-3200 175);
DISPLAY INVISIBLE (-3200 175);
FORCEPROP 2 LAST PATH I12
J 0
(-3575 325);
DISPLAY 0.680851 (-3575 325);
DISPLAY INVISIBLE (-3575 325);
FORCEADD OFFPAGE..1
(-3325 175);
FORCEPROP 2 LAST $XR0 353 
J 0
(-3607 175);
DISPLAY 0.638298 (-3607 175);
PAINT MONO (-3607 175);
FORCEPROP 2 LAST CDS_LIB standard
J 0
(-3325 175);
DISPLAY INVISIBLE (-3325 175);
FORCEPROP 1 LAST OFFPAGE TRUE
J 0
(-3000 50);
DISPLAY 0.872340 (-3000 50);
PAINT AQUA (-3000 50);
DISPLAY INVISIBLE (-3000 50);
FORCEPROP 1 LAST COMMENT_BODY TRUE
J 0
(-3200 75);
DISPLAY 0.872340 (-3200 75);
PAINT GREEN (-3200 75);
DISPLAY INVISIBLE (-3200 75);
FORCEPROP 2 LAST PATH I13
J 0
(-3575 225);
DISPLAY 0.680851 (-3575 225);
DISPLAY INVISIBLE (-3575 225);
FORCEADD OFFPAGE..1
(-3325 325);
FORCEPROP 2 LAST $XR0 342 
J 0
(-3607 325);
DISPLAY 0.638298 (-3607 325);
PAINT MONO (-3607 325);
FORCEPROP 2 LAST CDS_LIB standard
J 0
(-3325 325);
DISPLAY INVISIBLE (-3325 325);
FORCEPROP 1 LAST OFFPAGE TRUE
J 0
(-3000 200);
DISPLAY 0.872340 (-3000 200);
PAINT AQUA (-3000 200);
DISPLAY INVISIBLE (-3000 200);
FORCEPROP 1 LAST COMMENT_BODY TRUE
J 0
(-3200 225);
DISPLAY 0.872340 (-3200 225);
PAINT GREEN (-3200 225);
DISPLAY INVISIBLE (-3200 225);
FORCEPROP 2 LAST PATH I14
J 0
(-3575 375);
DISPLAY 0.680851 (-3575 375);
DISPLAY INVISIBLE (-3575 375);
FORCEADD UNIVERSAL_GND..1
(-2225 -1125);
FORCEPROP 3 LASTPIN (-2225 -1075) SIG_NAME GND\g
J 0
(-2215 -1065);
DISPLAY 0.659574 (-2215 -1065);
PAINT MONO (-2215 -1065);
DISPLAY INVISIBLE (-2215 -1065);
FORCEPROP 2 LAST CDS_LIB pure_quanta_power
J 0
(-2225 -1125);
DISPLAY INVISIBLE (-2225 -1125);
FORCEPROP 1 LAST HDL_POWER GND
J 1
(-2200 -1200);
DISPLAY 0.872340 (-2200 -1200);
PAINT GREEN (-2200 -1200);
DISPLAY INVISIBLE (-2200 -1200);
FORCEPROP 1 LAST PATH I15
J 0
(-2150 -1125);
DISPLAY 0.872340 (-2150 -1125);
PAINT AQUA (-2150 -1125);
DISPLAY INVISIBLE (-2150 -1125);
FORCEADD CONN112_10137002101LF..1
(-1125 775);
FORCEPROP 1 LAST LOCATION J109
J 0
(-1875 2575);
DISPLAY 0.723404 (-1875 2575);
PAINT GREEN (-1875 2575);
FORCEPROP 0 LAST $SEC 1
J 0
(-1875 2700);
DISPLAY 0.680851 (-1875 2700);
PAINT MONO (-1875 2700);
DISPLAY INVISIBLE (-1875 2700);
FORCEPROP 0 LAST CDS_SEC 1
J 0
(-1875 2700);
DISPLAY 1.021277 (-1875 2700);
DISPLAY INVISIBLE (-1875 2700);
FORCEPROP 0 LASTPIN (-2050 -125) $PN A5
J 2
(-2060 -115);
DISPLAY 0.680851 (-2060 -115);
PAINT MONO (-2060 -115);
FORCEPROP 0 LASTPIN (-2050 675) $PN A6
J 2
(-2060 685);
DISPLAY 0.680851 (-2060 685);
PAINT MONO (-2060 685);
FORCEPROP 0 LASTPIN (-2050 1475) $PN A7
J 2
(-2060 1485);
DISPLAY 0.680851 (-2060 1485);
PAINT MONO (-2060 1485);
FORCEPROP 0 LASTPIN (-2050 2275) $PN A8
J 2
(-2060 2285);
DISPLAY 0.680851 (-2060 2285);
PAINT MONO (-2060 2285);
FORCEPROP 0 LASTPIN (-2050 -175) $PN B5
J 2
(-2060 -165);
DISPLAY 0.680851 (-2060 -165);
PAINT MONO (-2060 -165);
FORCEPROP 0 LASTPIN (-2050 625) $PN B6
J 2
(-2060 635);
DISPLAY 0.680851 (-2060 635);
PAINT MONO (-2060 635);
FORCEPROP 0 LASTPIN (-2050 1425) $PN B7
J 2
(-2060 1435);
DISPLAY 0.680851 (-2060 1435);
PAINT MONO (-2060 1435);
FORCEPROP 0 LASTPIN (-2050 2225) $PN B8
J 2
(-2060 2235);
DISPLAY 0.680851 (-2060 2235);
PAINT MONO (-2060 2235);
FORCEPROP 0 LASTPIN (-2050 -225) $PN C5
J 2
(-2060 -215);
DISPLAY 0.680851 (-2060 -215);
PAINT MONO (-2060 -215);
FORCEPROP 0 LASTPIN (-2050 575) $PN C6
J 2
(-2060 585);
DISPLAY 0.680851 (-2060 585);
PAINT MONO (-2060 585);
FORCEPROP 0 LASTPIN (-2050 1375) $PN C7
J 2
(-2060 1385);
DISPLAY 0.680851 (-2060 1385);
PAINT MONO (-2060 1385);
FORCEPROP 0 LASTPIN (-2050 2175) $PN C8
J 2
(-2060 2185);
DISPLAY 0.680851 (-2060 2185);
PAINT MONO (-2060 2185);
FORCEPROP 0 LASTPIN (-2050 -275) $PN D5
J 2
(-2060 -265);
DISPLAY 0.680851 (-2060 -265);
PAINT MONO (-2060 -265);
FORCEPROP 0 LASTPIN (-2050 525) $PN D6
J 2
(-2060 535);
DISPLAY 0.680851 (-2060 535);
PAINT MONO (-2060 535);
FORCEPROP 0 LASTPIN (-2050 1325) $PN D7
J 2
(-2060 1335);
DISPLAY 0.680851 (-2060 1335);
PAINT MONO (-2060 1335);
FORCEPROP 0 LASTPIN (-2050 2125) $PN D8
J 2
(-2060 2135);
DISPLAY 0.680851 (-2060 2135);
PAINT MONO (-2060 2135);
FORCEPROP 0 LASTPIN (-2050 -325) $PN E5
J 2
(-2060 -315);
DISPLAY 0.680851 (-2060 -315);
PAINT MONO (-2060 -315);
FORCEPROP 0 LASTPIN (-2050 475) $PN E6
J 2
(-2060 485);
DISPLAY 0.680851 (-2060 485);
PAINT MONO (-2060 485);
FORCEPROP 0 LASTPIN (-2050 1275) $PN E7
J 2
(-2060 1285);
DISPLAY 0.680851 (-2060 1285);
PAINT MONO (-2060 1285);
FORCEPROP 0 LASTPIN (-2050 2075) $PN E8
J 2
(-2060 2085);
DISPLAY 0.680851 (-2060 2085);
PAINT MONO (-2060 2085);
FORCEPROP 0 LASTPIN (-2050 -375) $PN F5
J 2
(-2060 -365);
DISPLAY 0.680851 (-2060 -365);
PAINT MONO (-2060 -365);
FORCEPROP 0 LASTPIN (-2050 425) $PN F6
J 2
(-2060 435);
DISPLAY 0.680851 (-2060 435);
PAINT MONO (-2060 435);
FORCEPROP 0 LASTPIN (-2050 1225) $PN F7
J 2
(-2060 1235);
DISPLAY 0.680851 (-2060 1235);
PAINT MONO (-2060 1235);
FORCEPROP 0 LASTPIN (-2050 2025) $PN F8
J 2
(-2060 2035);
DISPLAY 0.680851 (-2060 2035);
PAINT MONO (-2060 2035);
FORCEPROP 0 LASTPIN (-2050 -425) $PN G5
J 2
(-2060 -415);
DISPLAY 0.680851 (-2060 -415);
PAINT MONO (-2060 -415);
FORCEPROP 0 LASTPIN (-2050 375) $PN G6
J 2
(-2060 385);
DISPLAY 0.680851 (-2060 385);
PAINT MONO (-2060 385);
FORCEPROP 0 LASTPIN (-2050 1175) $PN G7
J 2
(-2060 1185);
DISPLAY 0.680851 (-2060 1185);
PAINT MONO (-2060 1185);
FORCEPROP 0 LASTPIN (-2050 1975) $PN G8
J 2
(-2060 1985);
DISPLAY 0.680851 (-2060 1985);
PAINT MONO (-2060 1985);
FORCEPROP 0 LASTPIN (-2050 -475) $PN H5
J 2
(-2060 -465);
DISPLAY 0.680851 (-2060 -465);
PAINT MONO (-2060 -465);
FORCEPROP 0 LASTPIN (-2050 325) $PN H6
J 2
(-2060 335);
DISPLAY 0.680851 (-2060 335);
PAINT MONO (-2060 335);
FORCEPROP 0 LASTPIN (-2050 1125) $PN H7
J 2
(-2060 1135);
DISPLAY 0.680851 (-2060 1135);
PAINT MONO (-2060 1135);
FORCEPROP 0 LASTPIN (-2050 1925) $PN H8
J 2
(-2060 1935);
DISPLAY 0.680851 (-2060 1935);
PAINT MONO (-2060 1935);
FORCEPROP 0 LASTPIN (-2050 -525) $PN I5
J 2
(-2060 -515);
DISPLAY 0.680851 (-2060 -515);
PAINT MONO (-2060 -515);
FORCEPROP 0 LASTPIN (-2050 275) $PN I6
J 2
(-2060 285);
DISPLAY 0.680851 (-2060 285);
PAINT MONO (-2060 285);
FORCEPROP 0 LASTPIN (-2050 1075) $PN I7
J 2
(-2060 1085);
DISPLAY 0.680851 (-2060 1085);
PAINT MONO (-2060 1085);
FORCEPROP 0 LASTPIN (-2050 1875) $PN I8
J 2
(-2060 1885);
DISPLAY 0.680851 (-2060 1885);
PAINT MONO (-2060 1885);
FORCEPROP 0 LASTPIN (-2050 -575) $PN J5
J 2
(-2060 -565);
DISPLAY 0.680851 (-2060 -565);
PAINT MONO (-2060 -565);
FORCEPROP 0 LASTPIN (-2050 225) $PN J6
J 2
(-2060 235);
DISPLAY 0.680851 (-2060 235);
PAINT MONO (-2060 235);
FORCEPROP 0 LASTPIN (-2050 1025) $PN J7
J 2
(-2060 1035);
DISPLAY 0.680851 (-2060 1035);
PAINT MONO (-2060 1035);
FORCEPROP 0 LASTPIN (-2050 1825) $PN J8
J 2
(-2060 1835);
DISPLAY 0.680851 (-2060 1835);
PAINT MONO (-2060 1835);
FORCEPROP 0 LASTPIN (-2050 -625) $PN K5
J 2
(-2060 -615);
DISPLAY 0.680851 (-2060 -615);
PAINT MONO (-2060 -615);
FORCEPROP 0 LASTPIN (-2050 175) $PN K6
J 2
(-2060 185);
DISPLAY 0.680851 (-2060 185);
PAINT MONO (-2060 185);
FORCEPROP 0 LASTPIN (-2050 975) $PN K7
J 2
(-2060 985);
DISPLAY 0.680851 (-2060 985);
PAINT MONO (-2060 985);
FORCEPROP 0 LASTPIN (-2050 1775) $PN K8
J 2
(-2060 1785);
DISPLAY 0.680851 (-2060 1785);
PAINT MONO (-2060 1785);
FORCEPROP 0 LASTPIN (-2050 -675) $PN L5
J 2
(-2060 -665);
DISPLAY 0.680851 (-2060 -665);
PAINT MONO (-2060 -665);
FORCEPROP 0 LASTPIN (-2050 125) $PN L6
J 2
(-2060 135);
DISPLAY 0.680851 (-2060 135);
PAINT MONO (-2060 135);
FORCEPROP 0 LASTPIN (-2050 925) $PN L7
J 2
(-2060 935);
DISPLAY 0.680851 (-2060 935);
PAINT MONO (-2060 935);
FORCEPROP 0 LASTPIN (-2050 1725) $PN L8
J 2
(-2060 1735);
DISPLAY 0.680851 (-2060 1735);
PAINT MONO (-2060 1735);
FORCEPROP 0 LASTPIN (-2050 -725) $PN M5
J 2
(-2060 -715);
DISPLAY 0.680851 (-2060 -715);
PAINT MONO (-2060 -715);
FORCEPROP 0 LASTPIN (-2050 75) $PN M6
J 2
(-2060 85);
DISPLAY 0.680851 (-2060 85);
PAINT MONO (-2060 85);
FORCEPROP 0 LASTPIN (-2050 875) $PN M7
J 2
(-2060 885);
DISPLAY 0.680851 (-2060 885);
PAINT MONO (-2060 885);
FORCEPROP 0 LASTPIN (-2050 1675) $PN M8
J 2
(-2060 1685);
DISPLAY 0.680851 (-2060 1685);
PAINT MONO (-2060 1685);
FORCEPROP 0 LASTPIN (-2050 -775) $PN N5
J 2
(-2060 -765);
DISPLAY 0.680851 (-2060 -765);
PAINT MONO (-2060 -765);
FORCEPROP 0 LASTPIN (-2050 25) $PN N6
J 2
(-2060 35);
DISPLAY 0.680851 (-2060 35);
PAINT MONO (-2060 35);
FORCEPROP 0 LASTPIN (-2050 825) $PN N7
J 2
(-2060 835);
DISPLAY 0.680851 (-2060 835);
PAINT MONO (-2060 835);
FORCEPROP 0 LASTPIN (-2050 1625) $PN N8
J 2
(-2060 1635);
DISPLAY 0.680851 (-2060 1635);
PAINT MONO (-2060 1635);
FORCEPROP 1 LAST MATERIAL IO
J 0
(-1870 2457);
DISPLAY 0.723404 (-1870 2457);
PAINT GREEN (-1870 2457);
FORCEPROP 2 LAST PART_TYPE THLF
J 0
(-1875 2650);
DISPLAY 1.021277 (-1875 2650);
FORCEPROP 0 LAST VALUE CONN112_10137002-101LF
J 0
(-1850 2775);
DISPLAY 1.021277 (-1850 2775);
DISPLAY INVISIBLE (-1850 2775);
FORCEPROP 1 LAST NEEDS_NO_SIZE TRUE
J 0
(-1125 775);
DISPLAY 0.723404 (-1125 775);
PAINT GREEN (-1125 775);
DISPLAY INVISIBLE (-1125 775);
FORCEPROP 1 LAST CDS_LMAN_SYM_OUTLINE -775,1650,775,-1650
J 0
(-1125 775);
DISPLAY 0.468085 (-1125 775);
PAINT GREEN (-1125 775);
DISPLAY INVISIBLE (-1125 775);
FORCEPROP 2 LAST CDS_LIB pure_quanta
J 0
(-1125 775);
DISPLAY INVISIBLE (-1125 775);
FORCEPROP 1 LAST PATH I16
J 0
(-1125 775);
DISPLAY 0.723404 (-1125 775);
PAINT GREEN (-1125 775);
DISPLAY INVISIBLE (-1125 775);
FORCEPROP 1 LAST PART_NUMBER DFHSB2FR012
J 0
(-1875 2525);
DISPLAY 0.723404 (-1875 2525);
PAINT GREEN (-1875 2525);
DISPLAY INVISIBLE (-1875 2525);
FORCEADD OFFPAGE..2
R 2
(-3325 475);
FORCEPROP 2 LAST $XR0 352 
J 0
(-3580 475);
DISPLAY 0.638298 (-3580 475);
PAINT MONO (-3580 475);
FORCEPROP 2 LAST CDS_LIB standard
J 0
(-3325 475);
DISPLAY INVISIBLE (-3325 475);
FORCEPROP 1 LAST OFFPAGE TRUE
J 2
(-3650 350);
DISPLAY 0.872340 (-3650 350);
PAINT AQUA (-3650 350);
DISPLAY INVISIBLE (-3650 350);
FORCEPROP 1 LAST COMMENT_BODY TRUE
J 2
(-3280 380);
DISPLAY 0.872340 (-3280 380);
PAINT GREEN (-3280 380);
DISPLAY INVISIBLE (-3280 380);
FORCEPROP 2 LAST PATH I17
J 0
(-3600 525);
DISPLAY 0.680851 (-3600 525);
DISPLAY INVISIBLE (-3600 525);
FORCEADD OFFPAGE..5
(-3325 425);
FORCEPROP 2 LAST $XR0 352 
J 0
(-3580 425);
DISPLAY 0.638298 (-3580 425);
PAINT MONO (-3580 425);
FORCEPROP 2 LAST CDS_LIB standard
J 0
(-3325 425);
DISPLAY INVISIBLE (-3325 425);
FORCEPROP 1 LAST OFFPAGE TRUE
J 0
(-3000 300);
DISPLAY 0.872340 (-3000 300);
PAINT AQUA (-3000 300);
DISPLAY INVISIBLE (-3000 300);
FORCEPROP 1 LAST COMMENT_BODY TRUE
J 0
(-3225 350);
DISPLAY 1.170213 (-3225 350);
PAINT GREEN (-3225 350);
DISPLAY INVISIBLE (-3225 350);
FORCEPROP 2 LAST PATH I18
J 0
(-3600 475);
DISPLAY 0.680851 (-3600 475);
DISPLAY INVISIBLE (-3600 475);
FORCEADD OFFPAGE..5
(-3325 575);
FORCEPROP 2 LAST $XR0 341 
J 0
(-3580 575);
DISPLAY 0.638298 (-3580 575);
PAINT MONO (-3580 575);
FORCEPROP 2 LAST CDS_LIB standard
J 0
(-3325 575);
DISPLAY INVISIBLE (-3325 575);
FORCEPROP 1 LAST OFFPAGE TRUE
J 0
(-3000 450);
DISPLAY 0.872340 (-3000 450);
PAINT AQUA (-3000 450);
DISPLAY INVISIBLE (-3000 450);
FORCEPROP 1 LAST COMMENT_BODY TRUE
J 0
(-3225 500);
DISPLAY 1.170213 (-3225 500);
PAINT GREEN (-3225 500);
DISPLAY INVISIBLE (-3225 500);
FORCEPROP 2 LAST PATH I19
J 0
(-3600 625);
DISPLAY 0.680851 (-3600 625);
DISPLAY INVISIBLE (-3600 625);
FORCEADD OFFPAGE..1
(-3325 -675);
FORCEPROP 2 LAST $XR0 353 
J 0
(-3607 -675);
DISPLAY 0.638298 (-3607 -675);
PAINT MONO (-3607 -675);
FORCEPROP 2 LAST CDS_LIB standard
J 0
(-3325 -675);
DISPLAY INVISIBLE (-3325 -675);
FORCEPROP 1 LAST OFFPAGE TRUE
J 0
(-3000 -800);
DISPLAY 0.872340 (-3000 -800);
PAINT AQUA (-3000 -800);
DISPLAY INVISIBLE (-3000 -800);
FORCEPROP 1 LAST COMMENT_BODY TRUE
J 0
(-3200 -775);
DISPLAY 0.872340 (-3200 -775);
PAINT GREEN (-3200 -775);
DISPLAY INVISIBLE (-3200 -775);
FORCEPROP 2 LAST PATH I2
J 0
(-3575 -625);
DISPLAY 0.680851 (-3575 -625);
DISPLAY INVISIBLE (-3575 -625);
FORCEADD OFFPAGE..2
R 2
(-3325 625);
FORCEPROP 2 LAST $XR0 341 
J 0
(-3580 625);
DISPLAY 0.638298 (-3580 625);
PAINT MONO (-3580 625);
FORCEPROP 2 LAST CDS_LIB standard
J 0
(-3325 625);
DISPLAY INVISIBLE (-3325 625);
FORCEPROP 1 LAST OFFPAGE TRUE
J 2
(-3650 500);
DISPLAY 0.872340 (-3650 500);
PAINT AQUA (-3650 500);
DISPLAY INVISIBLE (-3650 500);
FORCEPROP 1 LAST COMMENT_BODY TRUE
J 2
(-3280 530);
DISPLAY 0.872340 (-3280 530);
PAINT GREEN (-3280 530);
DISPLAY INVISIBLE (-3280 530);
FORCEPROP 2 LAST PATH I20
J 0
(-3600 675);
DISPLAY 0.680851 (-3600 675);
DISPLAY INVISIBLE (-3600 675);
FORCEADD OFFPAGE..1
(-3325 875);
FORCEPROP 2 LAST $XR0 353 
J 0
(-3607 875);
DISPLAY 0.638298 (-3607 875);
PAINT MONO (-3607 875);
FORCEPROP 2 LAST CDS_LIB standard
J 0
(-3325 875);
DISPLAY INVISIBLE (-3325 875);
FORCEPROP 1 LAST OFFPAGE TRUE
J 0
(-3000 750);
DISPLAY 0.872340 (-3000 750);
PAINT AQUA (-3000 750);
DISPLAY INVISIBLE (-3000 750);
FORCEPROP 1 LAST COMMENT_BODY TRUE
J 0
(-3200 775);
DISPLAY 0.872340 (-3200 775);
PAINT GREEN (-3200 775);
DISPLAY INVISIBLE (-3200 775);
FORCEPROP 2 LAST PATH I21
J 0
(-3575 925);
DISPLAY 0.680851 (-3575 925);
DISPLAY INVISIBLE (-3575 925);
FORCEADD OFFPAGE..1
(-3325 925);
FORCEPROP 2 LAST $XR0 353 
J 0
(-3607 925);
DISPLAY 0.638298 (-3607 925);
PAINT MONO (-3607 925);
FORCEPROP 2 LAST CDS_LIB standard
J 0
(-3325 925);
DISPLAY INVISIBLE (-3325 925);
FORCEPROP 1 LAST OFFPAGE TRUE
J 0
(-3000 800);
DISPLAY 0.872340 (-3000 800);
PAINT AQUA (-3000 800);
DISPLAY INVISIBLE (-3000 800);
FORCEPROP 1 LAST COMMENT_BODY TRUE
J 0
(-3200 825);
DISPLAY 0.872340 (-3200 825);
PAINT GREEN (-3200 825);
DISPLAY INVISIBLE (-3200 825);
FORCEPROP 2 LAST PATH I22
J 0
(-3575 975);
DISPLAY 0.680851 (-3575 975);
DISPLAY INVISIBLE (-3575 975);
FORCEADD OFFPAGE..1
(-3325 1025);
FORCEPROP 2 LAST $XR0 342 
J 0
(-3607 1025);
DISPLAY 0.638298 (-3607 1025);
PAINT MONO (-3607 1025);
FORCEPROP 2 LAST CDS_LIB standard
J 0
(-3325 1025);
DISPLAY INVISIBLE (-3325 1025);
FORCEPROP 1 LAST OFFPAGE TRUE
J 0
(-3000 900);
DISPLAY 0.872340 (-3000 900);
PAINT AQUA (-3000 900);
DISPLAY INVISIBLE (-3000 900);
FORCEPROP 1 LAST COMMENT_BODY TRUE
J 0
(-3200 925);
DISPLAY 0.872340 (-3200 925);
PAINT GREEN (-3200 925);
DISPLAY INVISIBLE (-3200 925);
FORCEPROP 2 LAST PATH I23
J 0
(-3575 1075);
DISPLAY 0.680851 (-3575 1075);
DISPLAY INVISIBLE (-3575 1075);
FORCEADD OFFPAGE..1
(-3325 1075);
FORCEPROP 2 LAST $XR0 342 
J 0
(-3607 1075);
DISPLAY 0.638298 (-3607 1075);
PAINT MONO (-3607 1075);
FORCEPROP 2 LAST CDS_LIB standard
J 0
(-3325 1075);
DISPLAY INVISIBLE (-3325 1075);
FORCEPROP 1 LAST OFFPAGE TRUE
J 0
(-3000 950);
DISPLAY 0.872340 (-3000 950);
PAINT AQUA (-3000 950);
DISPLAY INVISIBLE (-3000 950);
FORCEPROP 1 LAST COMMENT_BODY TRUE
J 0
(-3200 975);
DISPLAY 0.872340 (-3200 975);
PAINT GREEN (-3200 975);
DISPLAY INVISIBLE (-3200 975);
FORCEPROP 2 LAST PATH I24
J 0
(-3575 1125);
DISPLAY 0.680851 (-3575 1125);
DISPLAY INVISIBLE (-3575 1125);
FORCEADD OFFPAGE..5
(-3325 1175);
FORCEPROP 2 LAST $XR0 352 
J 0
(-3580 1175);
DISPLAY 0.638298 (-3580 1175);
PAINT MONO (-3580 1175);
FORCEPROP 2 LAST CDS_LIB standard
J 0
(-3325 1175);
DISPLAY INVISIBLE (-3325 1175);
FORCEPROP 1 LAST OFFPAGE TRUE
J 0
(-3000 1050);
DISPLAY 0.872340 (-3000 1050);
PAINT AQUA (-3000 1050);
DISPLAY INVISIBLE (-3000 1050);
FORCEPROP 1 LAST COMMENT_BODY TRUE
J 0
(-3225 1100);
DISPLAY 1.170213 (-3225 1100);
PAINT GREEN (-3225 1100);
DISPLAY INVISIBLE (-3225 1100);
FORCEPROP 2 LAST PATH I25
J 0
(-3600 1225);
DISPLAY 0.680851 (-3600 1225);
DISPLAY INVISIBLE (-3600 1225);
FORCEADD OFFPAGE..2
R 2
(-3325 1225);
FORCEPROP 2 LAST $XR0 352 
J 0
(-3580 1225);
DISPLAY 0.638298 (-3580 1225);
PAINT MONO (-3580 1225);
FORCEPROP 2 LAST CDS_LIB standard
J 0
(-3325 1225);
DISPLAY INVISIBLE (-3325 1225);
FORCEPROP 1 LAST OFFPAGE TRUE
J 2
(-3650 1100);
DISPLAY 0.872340 (-3650 1100);
PAINT AQUA (-3650 1100);
DISPLAY INVISIBLE (-3650 1100);
FORCEPROP 1 LAST COMMENT_BODY TRUE
J 2
(-3280 1130);
DISPLAY 0.872340 (-3280 1130);
PAINT GREEN (-3280 1130);
DISPLAY INVISIBLE (-3280 1130);
FORCEPROP 2 LAST PATH I26
J 0
(-3600 1275);
DISPLAY 0.680851 (-3600 1275);
DISPLAY INVISIBLE (-3600 1275);
FORCEADD OFFPAGE..5
(-3325 1325);
FORCEPROP 2 LAST $XR0 341 
J 0
(-3580 1325);
DISPLAY 0.638298 (-3580 1325);
PAINT MONO (-3580 1325);
FORCEPROP 2 LAST CDS_LIB standard
J 0
(-3325 1325);
DISPLAY INVISIBLE (-3325 1325);
FORCEPROP 1 LAST OFFPAGE TRUE
J 0
(-3000 1200);
DISPLAY 0.872340 (-3000 1200);
PAINT AQUA (-3000 1200);
DISPLAY INVISIBLE (-3000 1200);
FORCEPROP 1 LAST COMMENT_BODY TRUE
J 0
(-3225 1250);
DISPLAY 1.170213 (-3225 1250);
PAINT GREEN (-3225 1250);
DISPLAY INVISIBLE (-3225 1250);
FORCEPROP 2 LAST PATH I27
J 0
(-3600 1375);
DISPLAY 0.680851 (-3600 1375);
DISPLAY INVISIBLE (-3600 1375);
FORCEADD OFFPAGE..2
R 2
(-3325 1375);
FORCEPROP 2 LAST $XR0 341 
J 0
(-3580 1375);
DISPLAY 0.638298 (-3580 1375);
PAINT MONO (-3580 1375);
FORCEPROP 2 LAST CDS_LIB standard
J 0
(-3325 1375);
DISPLAY INVISIBLE (-3325 1375);
FORCEPROP 1 LAST OFFPAGE TRUE
J 2
(-3650 1250);
DISPLAY 0.872340 (-3650 1250);
PAINT AQUA (-3650 1250);
DISPLAY INVISIBLE (-3650 1250);
FORCEPROP 1 LAST COMMENT_BODY TRUE
J 2
(-3280 1280);
DISPLAY 0.872340 (-3280 1280);
PAINT GREEN (-3280 1280);
DISPLAY INVISIBLE (-3280 1280);
FORCEPROP 2 LAST PATH I28
J 0
(-3600 1425);
DISPLAY 0.680851 (-3600 1425);
DISPLAY INVISIBLE (-3600 1425);
FORCEADD OFFPAGE..4
R 2
(-3325 1475);
FORCEPROP 2 LAST $XR0 249 
J 0
(-3607 1475);
DISPLAY 0.638298 (-3607 1475);
PAINT MONO (-3607 1475);
FORCEPROP 2 LAST CDS_LIB standard
J 0
(-3325 1475);
DISPLAY INVISIBLE (-3325 1475);
FORCEPROP 1 LAST OFFPAGE TRUE
J 2
(-3650 1350);
DISPLAY 0.872340 (-3650 1350);
PAINT GREEN (-3650 1350);
DISPLAY INVISIBLE (-3650 1350);
FORCEPROP 1 LAST COMMENT_BODY TRUE
J 2
(-3300 1375);
DISPLAY 0.872340 (-3300 1375);
PAINT GREEN (-3300 1375);
DISPLAY INVISIBLE (-3300 1375);
FORCEPROP 2 LAST PATH I29
J 0
(-3575 1525);
DISPLAY 0.680851 (-3575 1525);
DISPLAY INVISIBLE (-3575 1525);
FORCEADD OFFPAGE..1
(-3325 -525);
FORCEPROP 2 LAST $XR0 342 
J 0
(-3607 -525);
DISPLAY 0.638298 (-3607 -525);
PAINT MONO (-3607 -525);
FORCEPROP 2 LAST CDS_LIB standard
J 0
(-3325 -525);
DISPLAY INVISIBLE (-3325 -525);
FORCEPROP 1 LAST OFFPAGE TRUE
J 0
(-3000 -650);
DISPLAY 0.872340 (-3000 -650);
PAINT AQUA (-3000 -650);
DISPLAY INVISIBLE (-3000 -650);
FORCEPROP 1 LAST COMMENT_BODY TRUE
J 0
(-3200 -625);
DISPLAY 0.872340 (-3200 -625);
PAINT GREEN (-3200 -625);
DISPLAY INVISIBLE (-3200 -625);
FORCEPROP 2 LAST PATH I3
J 0
(-3575 -475);
DISPLAY 0.680851 (-3575 -475);
DISPLAY INVISIBLE (-3575 -475);
FORCEADD OFFPAGE..2
R 2
(-3325 1625);
FORCEPROP 2 LAST $XR0 125 
J 0
(-3580 1625);
DISPLAY 0.638298 (-3580 1625);
PAINT MONO (-3580 1625);
FORCEPROP 2 LAST CDS_LIB standard
J 0
(-3325 1625);
DISPLAY INVISIBLE (-3325 1625);
FORCEPROP 1 LAST OFFPAGE TRUE
J 2
(-3650 1500);
DISPLAY 0.872340 (-3650 1500);
PAINT AQUA (-3650 1500);
DISPLAY INVISIBLE (-3650 1500);
FORCEPROP 1 LAST COMMENT_BODY TRUE
J 2
(-3280 1530);
DISPLAY 0.872340 (-3280 1530);
PAINT GREEN (-3280 1530);
DISPLAY INVISIBLE (-3280 1530);
FORCEPROP 2 LAST PATH I30
J 0
(-3600 1675);
DISPLAY 0.680851 (-3600 1675);
DISPLAY INVISIBLE (-3600 1675);
FORCEADD OFFPAGE..1
(-3325 1775);
FORCEPROP 2 LAST $XR0 353 
J 0
(-3607 1775);
DISPLAY 0.638298 (-3607 1775);
PAINT MONO (-3607 1775);
FORCEPROP 2 LAST CDS_LIB standard
J 0
(-3325 1775);
DISPLAY INVISIBLE (-3325 1775);
FORCEPROP 1 LAST OFFPAGE TRUE
J 0
(-3000 1650);
DISPLAY 0.872340 (-3000 1650);
PAINT AQUA (-3000 1650);
DISPLAY INVISIBLE (-3000 1650);
FORCEPROP 1 LAST COMMENT_BODY TRUE
J 0
(-3200 1675);
DISPLAY 0.872340 (-3200 1675);
PAINT GREEN (-3200 1675);
DISPLAY INVISIBLE (-3200 1675);
FORCEPROP 2 LAST PATH I31
J 0
(-3575 1825);
DISPLAY 0.680851 (-3575 1825);
DISPLAY INVISIBLE (-3575 1825);
FORCEADD OFFPAGE..1
(-3325 1725);
FORCEPROP 2 LAST $XR0 353 
J 0
(-3607 1725);
DISPLAY 0.638298 (-3607 1725);
PAINT MONO (-3607 1725);
FORCEPROP 2 LAST CDS_LIB standard
J 0
(-3325 1725);
DISPLAY INVISIBLE (-3325 1725);
FORCEPROP 1 LAST OFFPAGE TRUE
J 0
(-3000 1600);
DISPLAY 0.872340 (-3000 1600);
PAINT AQUA (-3000 1600);
DISPLAY INVISIBLE (-3000 1600);
FORCEPROP 1 LAST COMMENT_BODY TRUE
J 0
(-3200 1625);
DISPLAY 0.872340 (-3200 1625);
PAINT GREEN (-3200 1625);
DISPLAY INVISIBLE (-3200 1625);
FORCEPROP 2 LAST PATH I32
J 0
(-3575 1775);
DISPLAY 0.680851 (-3575 1775);
DISPLAY INVISIBLE (-3575 1775);
FORCEADD OFFPAGE..1
(-3325 1875);
FORCEPROP 2 LAST $XR0 342 
J 0
(-3607 1875);
DISPLAY 0.638298 (-3607 1875);
PAINT MONO (-3607 1875);
FORCEPROP 2 LAST CDS_LIB standard
J 0
(-3325 1875);
DISPLAY INVISIBLE (-3325 1875);
FORCEPROP 1 LAST OFFPAGE TRUE
J 0
(-3000 1750);
DISPLAY 0.872340 (-3000 1750);
PAINT AQUA (-3000 1750);
DISPLAY INVISIBLE (-3000 1750);
FORCEPROP 1 LAST COMMENT_BODY TRUE
J 0
(-3200 1775);
DISPLAY 0.872340 (-3200 1775);
PAINT GREEN (-3200 1775);
DISPLAY INVISIBLE (-3200 1775);
FORCEPROP 2 LAST PATH I33
J 0
(-3575 1925);
DISPLAY 0.680851 (-3575 1925);
DISPLAY INVISIBLE (-3575 1925);
FORCEADD OFFPAGE..1
(-3325 1925);
FORCEPROP 2 LAST $XR0 342 
J 0
(-3607 1925);
DISPLAY 0.638298 (-3607 1925);
PAINT MONO (-3607 1925);
FORCEPROP 2 LAST CDS_LIB standard
J 0
(-3325 1925);
DISPLAY INVISIBLE (-3325 1925);
FORCEPROP 1 LAST OFFPAGE TRUE
J 0
(-3000 1800);
DISPLAY 0.872340 (-3000 1800);
PAINT AQUA (-3000 1800);
DISPLAY INVISIBLE (-3000 1800);
FORCEPROP 1 LAST COMMENT_BODY TRUE
J 0
(-3200 1825);
DISPLAY 0.872340 (-3200 1825);
PAINT GREEN (-3200 1825);
DISPLAY INVISIBLE (-3200 1825);
FORCEPROP 2 LAST PATH I34
J 0
(-3575 1975);
DISPLAY 0.680851 (-3575 1975);
DISPLAY INVISIBLE (-3575 1975);
FORCEADD OFFPAGE..5
(-3325 2025);
FORCEPROP 2 LAST $XR0 352 
J 0
(-3580 2025);
DISPLAY 0.638298 (-3580 2025);
PAINT MONO (-3580 2025);
FORCEPROP 2 LAST CDS_LIB standard
J 0
(-3325 2025);
DISPLAY INVISIBLE (-3325 2025);
FORCEPROP 1 LAST OFFPAGE TRUE
J 0
(-3000 1900);
DISPLAY 0.872340 (-3000 1900);
PAINT AQUA (-3000 1900);
DISPLAY INVISIBLE (-3000 1900);
FORCEPROP 1 LAST COMMENT_BODY TRUE
J 0
(-3225 1950);
DISPLAY 1.170213 (-3225 1950);
PAINT GREEN (-3225 1950);
DISPLAY INVISIBLE (-3225 1950);
FORCEPROP 2 LAST PATH I35
J 0
(-3600 2075);
DISPLAY 0.680851 (-3600 2075);
DISPLAY INVISIBLE (-3600 2075);
FORCEADD OFFPAGE..2
R 2
(-3325 2075);
FORCEPROP 2 LAST $XR0 352 
J 0
(-3580 2075);
DISPLAY 0.638298 (-3580 2075);
PAINT MONO (-3580 2075);
FORCEPROP 2 LAST CDS_LIB standard
J 0
(-3325 2075);
DISPLAY INVISIBLE (-3325 2075);
FORCEPROP 1 LAST OFFPAGE TRUE
J 2
(-3650 1950);
DISPLAY 0.872340 (-3650 1950);
PAINT AQUA (-3650 1950);
DISPLAY INVISIBLE (-3650 1950);
FORCEPROP 1 LAST COMMENT_BODY TRUE
J 2
(-3280 1980);
DISPLAY 0.872340 (-3280 1980);
PAINT GREEN (-3280 1980);
DISPLAY INVISIBLE (-3280 1980);
FORCEPROP 2 LAST PATH I36
J 0
(-3600 2125);
DISPLAY 0.680851 (-3600 2125);
DISPLAY INVISIBLE (-3600 2125);
FORCEADD OFFPAGE..2
R 2
(-3325 2225);
FORCEPROP 2 LAST $XR0 341 
J 0
(-3580 2225);
DISPLAY 0.638298 (-3580 2225);
PAINT MONO (-3580 2225);
FORCEPROP 2 LAST CDS_LIB standard
J 0
(-3325 2225);
DISPLAY INVISIBLE (-3325 2225);
FORCEPROP 1 LAST OFFPAGE TRUE
J 2
(-3650 2100);
DISPLAY 0.872340 (-3650 2100);
PAINT AQUA (-3650 2100);
DISPLAY INVISIBLE (-3650 2100);
FORCEPROP 1 LAST COMMENT_BODY TRUE
J 2
(-3280 2130);
DISPLAY 0.872340 (-3280 2130);
PAINT GREEN (-3280 2130);
DISPLAY INVISIBLE (-3280 2130);
FORCEPROP 2 LAST PATH I37
J 0
(-3600 2275);
DISPLAY 0.680851 (-3600 2275);
DISPLAY INVISIBLE (-3600 2275);
FORCEADD OFFPAGE..5
(-3325 2175);
FORCEPROP 2 LAST $XR0 341 
J 0
(-3580 2175);
DISPLAY 0.638298 (-3580 2175);
PAINT MONO (-3580 2175);
FORCEPROP 2 LAST CDS_LIB standard
J 0
(-3325 2175);
DISPLAY INVISIBLE (-3325 2175);
FORCEPROP 1 LAST OFFPAGE TRUE
J 0
(-3000 2050);
DISPLAY 0.872340 (-3000 2050);
PAINT AQUA (-3000 2050);
DISPLAY INVISIBLE (-3000 2050);
FORCEPROP 1 LAST COMMENT_BODY TRUE
J 0
(-3225 2100);
DISPLAY 1.170213 (-3225 2100);
PAINT GREEN (-3225 2100);
DISPLAY INVISIBLE (-3225 2100);
FORCEPROP 2 LAST PATH I38
J 0
(-3600 2225);
DISPLAY 0.680851 (-3600 2225);
DISPLAY INVISIBLE (-3600 2225);
FORCEADD OFFPAGE..1
(1450 -800);
FORCEPROP 2 LAST $XR0 353 
J 0
(1198 -800);
DISPLAY 0.638298 (1198 -800);
PAINT MONO (1198 -800);
FORCEPROP 2 LAST CDS_LIB standard
J 0
(1450 -800);
DISPLAY INVISIBLE (1450 -800);
FORCEPROP 1 LAST OFFPAGE TRUE
J 0
(1775 -925);
DISPLAY 0.872340 (1775 -925);
PAINT AQUA (1775 -925);
DISPLAY INVISIBLE (1775 -925);
FORCEPROP 1 LAST COMMENT_BODY TRUE
J 0
(1575 -900);
DISPLAY 0.872340 (1575 -900);
PAINT GREEN (1575 -900);
DISPLAY INVISIBLE (1575 -900);
FORCEPROP 2 LAST PATH I39
J 0
(1175 -750);
DISPLAY 0.680851 (1175 -750);
DISPLAY INVISIBLE (1175 -750);
FORCEADD OFFPAGE..5
(-3325 -425);
FORCEPROP 2 LAST $XR0 352 
J 0
(-3580 -425);
DISPLAY 0.638298 (-3580 -425);
PAINT MONO (-3580 -425);
FORCEPROP 2 LAST CDS_LIB standard
J 0
(-3325 -425);
DISPLAY INVISIBLE (-3325 -425);
FORCEPROP 1 LAST OFFPAGE TRUE
J 0
(-3000 -550);
DISPLAY 0.872340 (-3000 -550);
PAINT AQUA (-3000 -550);
DISPLAY INVISIBLE (-3000 -550);
FORCEPROP 1 LAST COMMENT_BODY TRUE
J 0
(-3225 -500);
DISPLAY 1.170213 (-3225 -500);
PAINT GREEN (-3225 -500);
DISPLAY INVISIBLE (-3225 -500);
FORCEPROP 2 LAST PATH I4
J 0
(-3600 -375);
DISPLAY 0.680851 (-3600 -375);
DISPLAY INVISIBLE (-3600 -375);
FORCEADD OFFPAGE..1
(1450 -750);
FORCEPROP 2 LAST $XR0 353 
J 0
(1198 -750);
DISPLAY 0.638298 (1198 -750);
PAINT MONO (1198 -750);
FORCEPROP 2 LAST CDS_LIB standard
J 0
(1450 -750);
DISPLAY INVISIBLE (1450 -750);
FORCEPROP 1 LAST OFFPAGE TRUE
J 0
(1775 -875);
DISPLAY 0.872340 (1775 -875);
PAINT AQUA (1775 -875);
DISPLAY INVISIBLE (1775 -875);
FORCEPROP 1 LAST COMMENT_BODY TRUE
J 0
(1575 -850);
DISPLAY 0.872340 (1575 -850);
PAINT GREEN (1575 -850);
DISPLAY INVISIBLE (1575 -850);
FORCEPROP 2 LAST PATH I40
J 0
(1175 -700);
DISPLAY 0.680851 (1175 -700);
DISPLAY INVISIBLE (1175 -700);
FORCEADD OFFPAGE..1
(1450 -650);
FORCEPROP 2 LAST $XR0 342 
J 0
(1198 -650);
DISPLAY 0.638298 (1198 -650);
PAINT MONO (1198 -650);
FORCEPROP 2 LAST CDS_LIB standard
J 0
(1450 -650);
DISPLAY INVISIBLE (1450 -650);
FORCEPROP 1 LAST OFFPAGE TRUE
J 0
(1775 -775);
DISPLAY 0.872340 (1775 -775);
PAINT AQUA (1775 -775);
DISPLAY INVISIBLE (1775 -775);
FORCEPROP 1 LAST COMMENT_BODY TRUE
J 0
(1575 -750);
DISPLAY 0.872340 (1575 -750);
PAINT GREEN (1575 -750);
DISPLAY INVISIBLE (1575 -750);
FORCEPROP 2 LAST PATH I41
J 0
(1175 -600);
DISPLAY 0.680851 (1175 -600);
DISPLAY INVISIBLE (1175 -600);
FORCEADD OFFPAGE..1
(1450 -600);
FORCEPROP 2 LAST $XR0 342 
J 0
(1198 -600);
DISPLAY 0.638298 (1198 -600);
PAINT MONO (1198 -600);
FORCEPROP 2 LAST CDS_LIB standard
J 0
(1450 -600);
DISPLAY INVISIBLE (1450 -600);
FORCEPROP 1 LAST OFFPAGE TRUE
J 0
(1775 -725);
DISPLAY 0.872340 (1775 -725);
PAINT AQUA (1775 -725);
DISPLAY INVISIBLE (1775 -725);
FORCEPROP 1 LAST COMMENT_BODY TRUE
J 0
(1575 -700);
DISPLAY 0.872340 (1575 -700);
PAINT GREEN (1575 -700);
DISPLAY INVISIBLE (1575 -700);
FORCEPROP 2 LAST PATH I42
J 0
(1175 -550);
DISPLAY 0.680851 (1175 -550);
DISPLAY INVISIBLE (1175 -550);
FORCEADD OFFPAGE..2
R 2
(1450 -450);
FORCEPROP 2 LAST $XR0 352 
J 0
(1165 -450);
DISPLAY 0.638298 (1165 -450);
PAINT MONO (1165 -450);
FORCEPROP 2 LAST CDS_LIB standard
J 0
(1450 -450);
DISPLAY INVISIBLE (1450 -450);
FORCEPROP 1 LAST OFFPAGE TRUE
J 2
(1125 -575);
DISPLAY 0.872340 (1125 -575);
PAINT AQUA (1125 -575);
DISPLAY INVISIBLE (1125 -575);
FORCEPROP 1 LAST COMMENT_BODY TRUE
J 2
(1495 -545);
DISPLAY 0.872340 (1495 -545);
PAINT GREEN (1495 -545);
DISPLAY INVISIBLE (1495 -545);
FORCEPROP 2 LAST PATH I43
J 0
(1200 -400);
DISPLAY 0.680851 (1200 -400);
DISPLAY INVISIBLE (1200 -400);
FORCEADD OFFPAGE..5
(1450 -500);
FORCEPROP 2 LAST $XR0 352 
J 0
(1165 -500);
DISPLAY 0.638298 (1165 -500);
PAINT MONO (1165 -500);
FORCEPROP 2 LAST CDS_LIB standard
J 0
(1450 -500);
DISPLAY INVISIBLE (1450 -500);
FORCEPROP 1 LAST OFFPAGE TRUE
J 0
(1775 -625);
DISPLAY 0.872340 (1775 -625);
PAINT AQUA (1775 -625);
DISPLAY INVISIBLE (1775 -625);
FORCEPROP 1 LAST COMMENT_BODY TRUE
J 0
(1550 -575);
DISPLAY 1.170213 (1550 -575);
PAINT GREEN (1550 -575);
DISPLAY INVISIBLE (1550 -575);
FORCEPROP 2 LAST PATH I44
J 0
(1200 -450);
DISPLAY 0.680851 (1200 -450);
DISPLAY INVISIBLE (1200 -450);
FORCEADD OFFPAGE..2
R 2
(1450 -300);
FORCEPROP 2 LAST $XR0 341 
J 0
(1165 -300);
DISPLAY 0.638298 (1165 -300);
PAINT MONO (1165 -300);
FORCEPROP 2 LAST CDS_LIB standard
J 0
(1450 -300);
DISPLAY INVISIBLE (1450 -300);
FORCEPROP 1 LAST OFFPAGE TRUE
J 2
(1125 -425);
DISPLAY 0.872340 (1125 -425);
PAINT AQUA (1125 -425);
DISPLAY INVISIBLE (1125 -425);
FORCEPROP 1 LAST COMMENT_BODY TRUE
J 2
(1495 -395);
DISPLAY 0.872340 (1495 -395);
PAINT GREEN (1495 -395);
DISPLAY INVISIBLE (1495 -395);
FORCEPROP 2 LAST PATH I45
J 0
(1200 -250);
DISPLAY 0.680851 (1200 -250);
DISPLAY INVISIBLE (1200 -250);
FORCEADD OFFPAGE..5
(1450 -350);
FORCEPROP 2 LAST $XR0 341 
J 0
(1165 -350);
DISPLAY 0.638298 (1165 -350);
PAINT MONO (1165 -350);
FORCEPROP 2 LAST CDS_LIB standard
J 0
(1450 -350);
DISPLAY INVISIBLE (1450 -350);
FORCEPROP 1 LAST OFFPAGE TRUE
J 0
(1775 -475);
DISPLAY 0.872340 (1775 -475);
PAINT AQUA (1775 -475);
DISPLAY INVISIBLE (1775 -475);
FORCEPROP 1 LAST COMMENT_BODY TRUE
J 0
(1550 -425);
DISPLAY 1.170213 (1550 -425);
PAINT GREEN (1550 -425);
DISPLAY INVISIBLE (1550 -425);
FORCEPROP 2 LAST PATH I46
J 0
(1200 -300);
DISPLAY 0.680851 (1200 -300);
DISPLAY INVISIBLE (1200 -300);
FORCEADD OFFPAGE..4
R 2
(1450 -200);
FORCEPROP 2 LAST $XR0 130 
J 0
(1198 -200);
DISPLAY 0.638298 (1198 -200);
PAINT MONO (1198 -200);
FORCEPROP 2 LAST CDS_LIB standard
J 0
(1450 -200);
DISPLAY INVISIBLE (1450 -200);
FORCEPROP 1 LAST OFFPAGE TRUE
J 2
(1125 -325);
DISPLAY 0.872340 (1125 -325);
PAINT GREEN (1125 -325);
DISPLAY INVISIBLE (1125 -325);
FORCEPROP 1 LAST COMMENT_BODY TRUE
J 2
(1475 -300);
DISPLAY 0.872340 (1475 -300);
PAINT GREEN (1475 -300);
DISPLAY INVISIBLE (1475 -300);
FORCEPROP 2 LAST PATH I47
J 0
(1175 -150);
DISPLAY 0.680851 (1175 -150);
DISPLAY INVISIBLE (1175 -150);
FORCEADD OFFPAGE..2
R 2
(1450 -50);
FORCEPROP 2 LAST $XR0 126 
J 0
(1165 -50);
DISPLAY 0.638298 (1165 -50);
PAINT MONO (1165 -50);
FORCEPROP 2 LAST CDS_LIB standard
J 0
(1450 -50);
DISPLAY INVISIBLE (1450 -50);
FORCEPROP 1 LAST OFFPAGE TRUE
J 2
(1125 -175);
DISPLAY 0.872340 (1125 -175);
PAINT AQUA (1125 -175);
DISPLAY INVISIBLE (1125 -175);
FORCEPROP 1 LAST COMMENT_BODY TRUE
J 2
(1495 -145);
DISPLAY 0.872340 (1495 -145);
PAINT GREEN (1495 -145);
DISPLAY INVISIBLE (1495 -145);
FORCEPROP 2 LAST PATH I48
J 0
(1200 0);
DISPLAY 0.680851 (1200 0);
DISPLAY INVISIBLE (1200 0);
FORCEADD OFFPAGE..1
(1450 50);
FORCEPROP 2 LAST $XR0 353 
J 0
(1198 50);
DISPLAY 0.638298 (1198 50);
PAINT MONO (1198 50);
FORCEPROP 2 LAST CDS_LIB standard
J 0
(1450 50);
DISPLAY INVISIBLE (1450 50);
FORCEPROP 1 LAST OFFPAGE TRUE
J 0
(1775 -75);
DISPLAY 0.872340 (1775 -75);
PAINT AQUA (1775 -75);
DISPLAY INVISIBLE (1775 -75);
FORCEPROP 1 LAST COMMENT_BODY TRUE
J 0
(1575 -50);
DISPLAY 0.872340 (1575 -50);
PAINT GREEN (1575 -50);
DISPLAY INVISIBLE (1575 -50);
FORCEPROP 2 LAST PATH I49
J 0
(1175 100);
DISPLAY 0.680851 (1175 100);
DISPLAY INVISIBLE (1175 100);
FORCEADD OFFPAGE..1
(-3325 -575);
FORCEPROP 2 LAST $XR0 342 
J 0
(-3607 -575);
DISPLAY 0.638298 (-3607 -575);
PAINT MONO (-3607 -575);
FORCEPROP 2 LAST CDS_LIB standard
J 0
(-3325 -575);
DISPLAY INVISIBLE (-3325 -575);
FORCEPROP 1 LAST OFFPAGE TRUE
J 0
(-3000 -700);
DISPLAY 0.872340 (-3000 -700);
PAINT AQUA (-3000 -700);
DISPLAY INVISIBLE (-3000 -700);
FORCEPROP 1 LAST COMMENT_BODY TRUE
J 0
(-3200 -675);
DISPLAY 0.872340 (-3200 -675);
PAINT GREEN (-3200 -675);
DISPLAY INVISIBLE (-3200 -675);
FORCEPROP 2 LAST PATH I5
J 0
(-3575 -525);
DISPLAY 0.680851 (-3575 -525);
DISPLAY INVISIBLE (-3575 -525);
FORCEADD OFFPAGE..1
(1450 100);
FORCEPROP 2 LAST $XR0 353 
J 0
(1198 100);
DISPLAY 0.638298 (1198 100);
PAINT MONO (1198 100);
FORCEPROP 2 LAST CDS_LIB standard
J 0
(1450 100);
DISPLAY INVISIBLE (1450 100);
FORCEPROP 1 LAST OFFPAGE TRUE
J 0
(1775 -25);
DISPLAY 0.872340 (1775 -25);
PAINT AQUA (1775 -25);
DISPLAY INVISIBLE (1775 -25);
FORCEPROP 1 LAST COMMENT_BODY TRUE
J 0
(1575 0);
DISPLAY 0.872340 (1575 0);
PAINT GREEN (1575 0);
DISPLAY INVISIBLE (1575 0);
FORCEPROP 2 LAST PATH I50
J 0
(1175 150);
DISPLAY 0.680851 (1175 150);
DISPLAY INVISIBLE (1175 150);
FORCEADD OFFPAGE..1
(1450 250);
FORCEPROP 2 LAST $XR0 342 
J 0
(1198 250);
DISPLAY 0.638298 (1198 250);
PAINT MONO (1198 250);
FORCEPROP 2 LAST CDS_LIB standard
J 0
(1450 250);
DISPLAY INVISIBLE (1450 250);
FORCEPROP 1 LAST OFFPAGE TRUE
J 0
(1775 125);
DISPLAY 0.872340 (1775 125);
PAINT AQUA (1775 125);
DISPLAY INVISIBLE (1775 125);
FORCEPROP 1 LAST COMMENT_BODY TRUE
J 0
(1575 150);
DISPLAY 0.872340 (1575 150);
PAINT GREEN (1575 150);
DISPLAY INVISIBLE (1575 150);
FORCEPROP 2 LAST PATH I51
J 0
(1175 300);
DISPLAY 0.680851 (1175 300);
DISPLAY INVISIBLE (1175 300);
FORCEADD OFFPAGE..1
(1450 200);
FORCEPROP 2 LAST $XR0 342 
J 0
(1198 200);
DISPLAY 0.638298 (1198 200);
PAINT MONO (1198 200);
FORCEPROP 2 LAST CDS_LIB standard
J 0
(1450 200);
DISPLAY INVISIBLE (1450 200);
FORCEPROP 1 LAST OFFPAGE TRUE
J 0
(1775 75);
DISPLAY 0.872340 (1775 75);
PAINT AQUA (1775 75);
DISPLAY INVISIBLE (1775 75);
FORCEPROP 1 LAST COMMENT_BODY TRUE
J 0
(1575 100);
DISPLAY 0.872340 (1575 100);
PAINT GREEN (1575 100);
DISPLAY INVISIBLE (1575 100);
FORCEPROP 2 LAST PATH I52
J 0
(1175 250);
DISPLAY 0.680851 (1175 250);
DISPLAY INVISIBLE (1175 250);
FORCEADD OFFPAGE..5
(1450 350);
FORCEPROP 2 LAST $XR0 352 
J 0
(1165 350);
DISPLAY 0.638298 (1165 350);
PAINT MONO (1165 350);
FORCEPROP 2 LAST CDS_LIB standard
J 0
(1450 350);
DISPLAY INVISIBLE (1450 350);
FORCEPROP 1 LAST OFFPAGE TRUE
J 0
(1775 225);
DISPLAY 0.872340 (1775 225);
PAINT AQUA (1775 225);
DISPLAY INVISIBLE (1775 225);
FORCEPROP 1 LAST COMMENT_BODY TRUE
J 0
(1550 275);
DISPLAY 1.170213 (1550 275);
PAINT GREEN (1550 275);
DISPLAY INVISIBLE (1550 275);
FORCEPROP 2 LAST PATH I53
J 0
(1200 400);
DISPLAY 0.680851 (1200 400);
DISPLAY INVISIBLE (1200 400);
FORCEADD UNIVERSAL_GND..1
(2500 -1250);
FORCEPROP 3 LASTPIN (2500 -1200) SIG_NAME GND\g
J 0
(2510 -1190);
DISPLAY 0.659574 (2510 -1190);
PAINT MONO (2510 -1190);
DISPLAY INVISIBLE (2510 -1190);
FORCEPROP 2 LAST CDS_LIB pure_quanta_power
J 0
(2500 -1250);
DISPLAY INVISIBLE (2500 -1250);
FORCEPROP 1 LAST HDL_POWER GND
J 1
(2525 -1325);
DISPLAY 0.872340 (2525 -1325);
PAINT GREEN (2525 -1325);
DISPLAY INVISIBLE (2525 -1325);
FORCEPROP 1 LAST PATH I54
J 0
(2575 -1250);
DISPLAY 0.872340 (2575 -1250);
PAINT AQUA (2575 -1250);
DISPLAY INVISIBLE (2575 -1250);
FORCEADD OFFPAGE..2
R 2
(1450 400);
FORCEPROP 2 LAST $XR0 352 
J 0
(1165 400);
DISPLAY 0.638298 (1165 400);
PAINT MONO (1165 400);
FORCEPROP 2 LAST CDS_LIB standard
J 0
(1450 400);
DISPLAY INVISIBLE (1450 400);
FORCEPROP 1 LAST OFFPAGE TRUE
J 2
(1125 275);
DISPLAY 0.872340 (1125 275);
PAINT AQUA (1125 275);
DISPLAY INVISIBLE (1125 275);
FORCEPROP 1 LAST COMMENT_BODY TRUE
J 2
(1495 305);
DISPLAY 0.872340 (1495 305);
PAINT GREEN (1495 305);
DISPLAY INVISIBLE (1495 305);
FORCEPROP 2 LAST PATH I55
J 0
(1200 450);
DISPLAY 0.680851 (1200 450);
DISPLAY INVISIBLE (1200 450);
FORCEADD OFFPAGE..5
(1450 500);
FORCEPROP 2 LAST $XR0 341 
J 0
(1165 500);
DISPLAY 0.638298 (1165 500);
PAINT MONO (1165 500);
FORCEPROP 2 LAST CDS_LIB standard
J 0
(1450 500);
DISPLAY INVISIBLE (1450 500);
FORCEPROP 1 LAST OFFPAGE TRUE
J 0
(1775 375);
DISPLAY 0.872340 (1775 375);
PAINT AQUA (1775 375);
DISPLAY INVISIBLE (1775 375);
FORCEPROP 1 LAST COMMENT_BODY TRUE
J 0
(1550 425);
DISPLAY 1.170213 (1550 425);
PAINT GREEN (1550 425);
DISPLAY INVISIBLE (1550 425);
FORCEPROP 2 LAST PATH I56
J 0
(1200 550);
DISPLAY 0.680851 (1200 550);
DISPLAY INVISIBLE (1200 550);
FORCEADD OFFPAGE..2
R 2
(1450 550);
FORCEPROP 2 LAST $XR0 341 
J 0
(1165 550);
DISPLAY 0.638298 (1165 550);
PAINT MONO (1165 550);
FORCEPROP 2 LAST CDS_LIB standard
J 0
(1450 550);
DISPLAY INVISIBLE (1450 550);
FORCEPROP 1 LAST OFFPAGE TRUE
J 2
(1125 425);
DISPLAY 0.872340 (1125 425);
PAINT AQUA (1125 425);
DISPLAY INVISIBLE (1125 425);
FORCEPROP 1 LAST COMMENT_BODY TRUE
J 2
(1495 455);
DISPLAY 0.872340 (1495 455);
PAINT GREEN (1495 455);
DISPLAY INVISIBLE (1495 455);
FORCEPROP 2 LAST PATH I57
J 0
(1200 600);
DISPLAY 0.680851 (1200 600);
DISPLAY INVISIBLE (1200 600);
FORCEADD OFFPAGE..1
(1425 800);
FORCEPROP 2 LAST $XR0 353 
J 0
(1173 800);
DISPLAY 0.638298 (1173 800);
PAINT MONO (1173 800);
FORCEPROP 2 LAST CDS_LIB standard
J 0
(1425 800);
DISPLAY INVISIBLE (1425 800);
FORCEPROP 1 LAST OFFPAGE TRUE
J 0
(1750 675);
DISPLAY 0.872340 (1750 675);
PAINT AQUA (1750 675);
DISPLAY INVISIBLE (1750 675);
FORCEPROP 1 LAST COMMENT_BODY TRUE
J 0
(1550 700);
DISPLAY 0.872340 (1550 700);
PAINT GREEN (1550 700);
DISPLAY INVISIBLE (1550 700);
FORCEPROP 2 LAST PATH I58
J 0
(1150 850);
DISPLAY 0.680851 (1150 850);
DISPLAY INVISIBLE (1150 850);
FORCEADD OFFPAGE..1
(1425 850);
FORCEPROP 2 LAST $XR0 353 
J 0
(1173 850);
DISPLAY 0.638298 (1173 850);
PAINT MONO (1173 850);
FORCEPROP 2 LAST CDS_LIB standard
J 0
(1425 850);
DISPLAY INVISIBLE (1425 850);
FORCEPROP 1 LAST OFFPAGE TRUE
J 0
(1750 725);
DISPLAY 0.872340 (1750 725);
PAINT AQUA (1750 725);
DISPLAY INVISIBLE (1750 725);
FORCEPROP 1 LAST COMMENT_BODY TRUE
J 0
(1550 750);
DISPLAY 0.872340 (1550 750);
PAINT GREEN (1550 750);
DISPLAY INVISIBLE (1550 750);
FORCEPROP 2 LAST PATH I59
J 0
(1150 900);
DISPLAY 0.680851 (1150 900);
DISPLAY INVISIBLE (1150 900);
FORCEADD OFFPAGE..2
R 2
(-3325 -375);
FORCEPROP 2 LAST $XR0 352 
J 0
(-3580 -375);
DISPLAY 0.638298 (-3580 -375);
PAINT MONO (-3580 -375);
FORCEPROP 2 LAST CDS_LIB standard
J 0
(-3325 -375);
DISPLAY INVISIBLE (-3325 -375);
FORCEPROP 1 LAST OFFPAGE TRUE
J 2
(-3650 -500);
DISPLAY 0.872340 (-3650 -500);
PAINT AQUA (-3650 -500);
DISPLAY INVISIBLE (-3650 -500);
FORCEPROP 1 LAST COMMENT_BODY TRUE
J 2
(-3280 -470);
DISPLAY 0.872340 (-3280 -470);
PAINT GREEN (-3280 -470);
DISPLAY INVISIBLE (-3280 -470);
FORCEPROP 2 LAST PATH I6
J 0
(-3600 -325);
DISPLAY 0.680851 (-3600 -325);
DISPLAY INVISIBLE (-3600 -325);
FORCEADD OFFPAGE..1
(1425 1000);
FORCEPROP 2 LAST $XR0 342 
J 0
(1173 1000);
DISPLAY 0.638298 (1173 1000);
PAINT MONO (1173 1000);
FORCEPROP 2 LAST CDS_LIB standard
J 0
(1425 1000);
DISPLAY INVISIBLE (1425 1000);
FORCEPROP 1 LAST OFFPAGE TRUE
J 0
(1750 875);
DISPLAY 0.872340 (1750 875);
PAINT AQUA (1750 875);
DISPLAY INVISIBLE (1750 875);
FORCEPROP 1 LAST COMMENT_BODY TRUE
J 0
(1550 900);
DISPLAY 0.872340 (1550 900);
PAINT GREEN (1550 900);
DISPLAY INVISIBLE (1550 900);
FORCEPROP 2 LAST PATH I60
J 0
(1150 1050);
DISPLAY 0.680851 (1150 1050);
DISPLAY INVISIBLE (1150 1050);
FORCEADD OFFPAGE..1
(1425 950);
FORCEPROP 2 LAST $XR0 342 
J 0
(1173 950);
DISPLAY 0.638298 (1173 950);
PAINT MONO (1173 950);
FORCEPROP 2 LAST CDS_LIB standard
J 0
(1425 950);
DISPLAY INVISIBLE (1425 950);
FORCEPROP 1 LAST OFFPAGE TRUE
J 0
(1750 825);
DISPLAY 0.872340 (1750 825);
PAINT AQUA (1750 825);
DISPLAY INVISIBLE (1750 825);
FORCEPROP 1 LAST COMMENT_BODY TRUE
J 0
(1550 850);
DISPLAY 0.872340 (1550 850);
PAINT GREEN (1550 850);
DISPLAY INVISIBLE (1550 850);
FORCEPROP 2 LAST PATH I61
J 0
(1150 1000);
DISPLAY 0.680851 (1150 1000);
DISPLAY INVISIBLE (1150 1000);
FORCEADD OFFPAGE..5
(1425 1100);
FORCEPROP 2 LAST $XR0 352 
J 0
(1170 1100);
DISPLAY 0.638298 (1170 1100);
PAINT MONO (1170 1100);
FORCEPROP 2 LAST CDS_LIB standard
J 0
(1425 1100);
DISPLAY INVISIBLE (1425 1100);
FORCEPROP 1 LAST OFFPAGE TRUE
J 0
(1750 975);
DISPLAY 0.872340 (1750 975);
PAINT AQUA (1750 975);
DISPLAY INVISIBLE (1750 975);
FORCEPROP 1 LAST COMMENT_BODY TRUE
J 0
(1525 1025);
DISPLAY 1.170213 (1525 1025);
PAINT GREEN (1525 1025);
DISPLAY INVISIBLE (1525 1025);
FORCEPROP 2 LAST PATH I62
J 0
(1175 1150);
DISPLAY 0.680851 (1175 1150);
DISPLAY INVISIBLE (1175 1150);
FORCEADD OFFPAGE..2
R 2
(1425 1150);
FORCEPROP 2 LAST $XR0 352 
J 0
(1170 1150);
DISPLAY 0.638298 (1170 1150);
PAINT MONO (1170 1150);
FORCEPROP 2 LAST CDS_LIB standard
J 0
(1425 1150);
DISPLAY INVISIBLE (1425 1150);
FORCEPROP 1 LAST OFFPAGE TRUE
J 2
(1100 1025);
DISPLAY 0.872340 (1100 1025);
PAINT AQUA (1100 1025);
DISPLAY INVISIBLE (1100 1025);
FORCEPROP 1 LAST COMMENT_BODY TRUE
J 2
(1470 1055);
DISPLAY 0.872340 (1470 1055);
PAINT GREEN (1470 1055);
DISPLAY INVISIBLE (1470 1055);
FORCEPROP 2 LAST PATH I63
J 0
(1175 1200);
DISPLAY 0.680851 (1175 1200);
DISPLAY INVISIBLE (1175 1200);
FORCEADD OFFPAGE..5
(1425 1250);
FORCEPROP 2 LAST $XR0 341 
J 0
(1170 1250);
DISPLAY 0.638298 (1170 1250);
PAINT MONO (1170 1250);
FORCEPROP 2 LAST CDS_LIB standard
J 0
(1425 1250);
DISPLAY INVISIBLE (1425 1250);
FORCEPROP 1 LAST OFFPAGE TRUE
J 0
(1750 1125);
DISPLAY 0.872340 (1750 1125);
PAINT AQUA (1750 1125);
DISPLAY INVISIBLE (1750 1125);
FORCEPROP 1 LAST COMMENT_BODY TRUE
J 0
(1525 1175);
DISPLAY 1.170213 (1525 1175);
PAINT GREEN (1525 1175);
DISPLAY INVISIBLE (1525 1175);
FORCEPROP 2 LAST PATH I64
J 0
(1175 1300);
DISPLAY 0.680851 (1175 1300);
DISPLAY INVISIBLE (1175 1300);
FORCEADD OFFPAGE..2
R 2
(1425 1300);
FORCEPROP 2 LAST $XR0 341 
J 0
(1170 1300);
DISPLAY 0.638298 (1170 1300);
PAINT MONO (1170 1300);
FORCEPROP 2 LAST CDS_LIB standard
J 0
(1425 1300);
DISPLAY INVISIBLE (1425 1300);
FORCEPROP 1 LAST OFFPAGE TRUE
J 2
(1100 1175);
DISPLAY 0.872340 (1100 1175);
PAINT AQUA (1100 1175);
DISPLAY INVISIBLE (1100 1175);
FORCEPROP 1 LAST COMMENT_BODY TRUE
J 2
(1470 1205);
DISPLAY 0.872340 (1470 1205);
PAINT GREEN (1470 1205);
DISPLAY INVISIBLE (1470 1205);
FORCEPROP 2 LAST PATH I65
J 0
(1175 1350);
DISPLAY 0.680851 (1175 1350);
DISPLAY INVISIBLE (1175 1350);
FORCEADD OFFPAGE..5
(1425 1400);
FORCEPROP 2 LAST $XR0 127 
J 0
(1170 1400);
DISPLAY 0.638298 (1170 1400);
PAINT MONO (1170 1400);
FORCEPROP 2 LAST CDS_LIB standard
J 0
(1425 1400);
DISPLAY INVISIBLE (1425 1400);
FORCEPROP 1 LAST OFFPAGE TRUE
J 0
(1750 1275);
DISPLAY 0.872340 (1750 1275);
PAINT AQUA (1750 1275);
DISPLAY INVISIBLE (1750 1275);
FORCEPROP 1 LAST COMMENT_BODY TRUE
J 0
(1525 1325);
DISPLAY 1.170213 (1525 1325);
PAINT GREEN (1525 1325);
DISPLAY INVISIBLE (1525 1325);
FORCEPROP 2 LAST PATH I66
J 0
(1175 1450);
DISPLAY 0.680851 (1175 1450);
DISPLAY INVISIBLE (1175 1450);
FORCEADD OFFPAGE..2
R 2
(1450 1550);
FORCEPROP 2 LAST $XR0 125 
J 0
(1165 1550);
DISPLAY 0.638298 (1165 1550);
PAINT MONO (1165 1550);
FORCEPROP 2 LAST CDS_LIB standard
J 0
(1450 1550);
DISPLAY INVISIBLE (1450 1550);
FORCEPROP 1 LAST OFFPAGE TRUE
J 2
(1125 1425);
DISPLAY 0.872340 (1125 1425);
PAINT AQUA (1125 1425);
DISPLAY INVISIBLE (1125 1425);
FORCEPROP 1 LAST COMMENT_BODY TRUE
J 2
(1495 1455);
DISPLAY 0.872340 (1495 1455);
PAINT GREEN (1495 1455);
DISPLAY INVISIBLE (1495 1455);
FORCEPROP 2 LAST PATH I67
J 0
(1200 1600);
DISPLAY 0.680851 (1200 1600);
DISPLAY INVISIBLE (1200 1600);
FORCEADD OFFPAGE..1
(1425 1650);
FORCEPROP 2 LAST $XR0 353 
J 0
(1173 1650);
DISPLAY 0.638298 (1173 1650);
PAINT MONO (1173 1650);
FORCEPROP 2 LAST CDS_LIB standard
J 0
(1425 1650);
DISPLAY INVISIBLE (1425 1650);
FORCEPROP 1 LAST OFFPAGE TRUE
J 0
(1750 1525);
DISPLAY 0.872340 (1750 1525);
PAINT AQUA (1750 1525);
DISPLAY INVISIBLE (1750 1525);
FORCEPROP 1 LAST COMMENT_BODY TRUE
J 0
(1550 1550);
DISPLAY 0.872340 (1550 1550);
PAINT GREEN (1550 1550);
DISPLAY INVISIBLE (1550 1550);
FORCEPROP 2 LAST PATH I68
J 0
(1150 1700);
DISPLAY 0.680851 (1150 1700);
DISPLAY INVISIBLE (1150 1700);
FORCEADD OFFPAGE..1
(1425 1800);
FORCEPROP 2 LAST $XR0 342 
J 0
(1173 1800);
DISPLAY 0.638298 (1173 1800);
PAINT MONO (1173 1800);
FORCEPROP 2 LAST CDS_LIB standard
J 0
(1425 1800);
DISPLAY INVISIBLE (1425 1800);
FORCEPROP 1 LAST OFFPAGE TRUE
J 0
(1750 1675);
DISPLAY 0.872340 (1750 1675);
PAINT AQUA (1750 1675);
DISPLAY INVISIBLE (1750 1675);
FORCEPROP 1 LAST COMMENT_BODY TRUE
J 0
(1550 1700);
DISPLAY 0.872340 (1550 1700);
PAINT GREEN (1550 1700);
DISPLAY INVISIBLE (1550 1700);
FORCEPROP 2 LAST PATH I69
J 0
(1150 1850);
DISPLAY 0.680851 (1150 1850);
DISPLAY INVISIBLE (1150 1850);
FORCEADD OFFPAGE..5
(-3325 -275);
FORCEPROP 2 LAST $XR0 341 
J 0
(-3580 -275);
DISPLAY 0.638298 (-3580 -275);
PAINT MONO (-3580 -275);
FORCEPROP 2 LAST CDS_LIB standard
J 0
(-3325 -275);
DISPLAY INVISIBLE (-3325 -275);
FORCEPROP 1 LAST OFFPAGE TRUE
J 0
(-3000 -400);
DISPLAY 0.872340 (-3000 -400);
PAINT AQUA (-3000 -400);
DISPLAY INVISIBLE (-3000 -400);
FORCEPROP 1 LAST COMMENT_BODY TRUE
J 0
(-3225 -350);
DISPLAY 1.170213 (-3225 -350);
PAINT GREEN (-3225 -350);
DISPLAY INVISIBLE (-3225 -350);
FORCEPROP 2 LAST PATH I7
J 0
(-3600 -225);
DISPLAY 0.680851 (-3600 -225);
DISPLAY INVISIBLE (-3600 -225);
FORCEADD OFFPAGE..1
(1425 1700);
FORCEPROP 2 LAST $XR0 353 
J 0
(1173 1700);
DISPLAY 0.638298 (1173 1700);
PAINT MONO (1173 1700);
FORCEPROP 2 LAST CDS_LIB standard
J 0
(1425 1700);
DISPLAY INVISIBLE (1425 1700);
FORCEPROP 1 LAST OFFPAGE TRUE
J 0
(1750 1575);
DISPLAY 0.872340 (1750 1575);
PAINT AQUA (1750 1575);
DISPLAY INVISIBLE (1750 1575);
FORCEPROP 1 LAST COMMENT_BODY TRUE
J 0
(1550 1600);
DISPLAY 0.872340 (1550 1600);
PAINT GREEN (1550 1600);
DISPLAY INVISIBLE (1550 1600);
FORCEPROP 2 LAST PATH I70
J 0
(1150 1750);
DISPLAY 0.680851 (1150 1750);
DISPLAY INVISIBLE (1150 1750);
FORCEADD OFFPAGE..1
(1425 1850);
FORCEPROP 2 LAST $XR0 342 
J 0
(1173 1850);
DISPLAY 0.638298 (1173 1850);
PAINT MONO (1173 1850);
FORCEPROP 2 LAST CDS_LIB standard
J 0
(1425 1850);
DISPLAY INVISIBLE (1425 1850);
FORCEPROP 1 LAST OFFPAGE TRUE
J 0
(1750 1725);
DISPLAY 0.872340 (1750 1725);
PAINT AQUA (1750 1725);
DISPLAY INVISIBLE (1750 1725);
FORCEPROP 1 LAST COMMENT_BODY TRUE
J 0
(1550 1750);
DISPLAY 0.872340 (1550 1750);
PAINT GREEN (1550 1750);
DISPLAY INVISIBLE (1550 1750);
FORCEPROP 2 LAST PATH I71
J 0
(1150 1900);
DISPLAY 0.680851 (1150 1900);
DISPLAY INVISIBLE (1150 1900);
FORCEADD OFFPAGE..5
(1425 1950);
FORCEPROP 2 LAST $XR0 352 
J 0
(1170 1950);
DISPLAY 0.638298 (1170 1950);
PAINT MONO (1170 1950);
FORCEPROP 2 LAST CDS_LIB standard
J 0
(1425 1950);
DISPLAY INVISIBLE (1425 1950);
FORCEPROP 1 LAST OFFPAGE TRUE
J 0
(1750 1825);
DISPLAY 0.872340 (1750 1825);
PAINT AQUA (1750 1825);
DISPLAY INVISIBLE (1750 1825);
FORCEPROP 1 LAST COMMENT_BODY TRUE
J 0
(1525 1875);
DISPLAY 1.170213 (1525 1875);
PAINT GREEN (1525 1875);
DISPLAY INVISIBLE (1525 1875);
FORCEPROP 2 LAST PATH I72
J 0
(1175 2000);
DISPLAY 0.680851 (1175 2000);
DISPLAY INVISIBLE (1175 2000);
FORCEADD OFFPAGE..2
R 2
(1425 2000);
FORCEPROP 2 LAST $XR0 352 
J 0
(1170 2000);
DISPLAY 0.638298 (1170 2000);
PAINT MONO (1170 2000);
FORCEPROP 2 LAST CDS_LIB standard
J 0
(1425 2000);
DISPLAY INVISIBLE (1425 2000);
FORCEPROP 1 LAST OFFPAGE TRUE
J 2
(1100 1875);
DISPLAY 0.872340 (1100 1875);
PAINT AQUA (1100 1875);
DISPLAY INVISIBLE (1100 1875);
FORCEPROP 1 LAST COMMENT_BODY TRUE
J 2
(1470 1905);
DISPLAY 0.872340 (1470 1905);
PAINT GREEN (1470 1905);
DISPLAY INVISIBLE (1470 1905);
FORCEPROP 2 LAST PATH I73
J 0
(1175 2050);
DISPLAY 0.680851 (1175 2050);
DISPLAY INVISIBLE (1175 2050);
FORCEADD OFFPAGE..5
(1425 2100);
FORCEPROP 2 LAST $XR0 341 
J 0
(1170 2100);
DISPLAY 0.638298 (1170 2100);
PAINT MONO (1170 2100);
FORCEPROP 2 LAST CDS_LIB standard
J 0
(1425 2100);
DISPLAY INVISIBLE (1425 2100);
FORCEPROP 1 LAST OFFPAGE TRUE
J 0
(1750 1975);
DISPLAY 0.872340 (1750 1975);
PAINT AQUA (1750 1975);
DISPLAY INVISIBLE (1750 1975);
FORCEPROP 1 LAST COMMENT_BODY TRUE
J 0
(1525 2025);
DISPLAY 1.170213 (1525 2025);
PAINT GREEN (1525 2025);
DISPLAY INVISIBLE (1525 2025);
FORCEPROP 2 LAST PATH I74
J 0
(1175 2150);
DISPLAY 0.680851 (1175 2150);
DISPLAY INVISIBLE (1175 2150);
FORCEADD OFFPAGE..2
R 2
(1425 2150);
FORCEPROP 2 LAST $XR0 341 
J 0
(1170 2150);
DISPLAY 0.638298 (1170 2150);
PAINT MONO (1170 2150);
FORCEPROP 2 LAST CDS_LIB standard
J 0
(1425 2150);
DISPLAY INVISIBLE (1425 2150);
FORCEPROP 1 LAST OFFPAGE TRUE
J 2
(1100 2025);
DISPLAY 0.872340 (1100 2025);
PAINT AQUA (1100 2025);
DISPLAY INVISIBLE (1100 2025);
FORCEPROP 1 LAST COMMENT_BODY TRUE
J 2
(1470 2055);
DISPLAY 0.872340 (1470 2055);
PAINT GREEN (1470 2055);
DISPLAY INVISIBLE (1470 2055);
FORCEPROP 2 LAST PATH I75
J 0
(1175 2200);
DISPLAY 0.680851 (1175 2200);
DISPLAY INVISIBLE (1175 2200);
FORCEADD CONN112_10137002101LF..2
(3650 700);
FORCEPROP 1 LAST LOCATION J109
J 0
(2900 2525);
DISPLAY 0.723404 (2900 2525);
PAINT GREEN (2900 2525);
FORCEPROP 0 LAST $SEC 2
J 0
(2900 2650);
DISPLAY 0.680851 (2900 2650);
PAINT MONO (2900 2650);
DISPLAY INVISIBLE (2900 2650);
FORCEPROP 0 LAST CDS_SEC 2
J 0
(2900 2650);
DISPLAY 1.021277 (2900 2650);
DISPLAY INVISIBLE (2900 2650);
FORCEPROP 0 LASTPIN (2725 -200) $PN A1
J 2
(2715 -190);
DISPLAY 0.680851 (2715 -190);
PAINT MONO (2715 -190);
FORCEPROP 0 LASTPIN (2725 600) $PN A2
J 2
(2715 610);
DISPLAY 0.680851 (2715 610);
PAINT MONO (2715 610);
FORCEPROP 0 LASTPIN (2725 1400) $PN A3
J 2
(2715 1410);
DISPLAY 0.680851 (2715 1410);
PAINT MONO (2715 1410);
FORCEPROP 0 LASTPIN (2725 2200) $PN A4
J 2
(2715 2210);
DISPLAY 0.680851 (2715 2210);
PAINT MONO (2715 2210);
FORCEPROP 0 LASTPIN (2725 -250) $PN B1
J 2
(2715 -240);
DISPLAY 0.680851 (2715 -240);
PAINT MONO (2715 -240);
FORCEPROP 0 LASTPIN (2725 550) $PN B2
J 2
(2715 560);
DISPLAY 0.680851 (2715 560);
PAINT MONO (2715 560);
FORCEPROP 0 LASTPIN (2725 1350) $PN B3
J 2
(2715 1360);
DISPLAY 0.680851 (2715 1360);
PAINT MONO (2715 1360);
FORCEPROP 0 LASTPIN (2725 2150) $PN B4
J 2
(2715 2160);
DISPLAY 0.680851 (2715 2160);
PAINT MONO (2715 2160);
FORCEPROP 0 LASTPIN (2725 -300) $PN C1
J 2
(2715 -290);
DISPLAY 0.680851 (2715 -290);
PAINT MONO (2715 -290);
FORCEPROP 0 LASTPIN (2725 500) $PN C2
J 2
(2715 510);
DISPLAY 0.680851 (2715 510);
PAINT MONO (2715 510);
FORCEPROP 0 LASTPIN (2725 1300) $PN C3
J 2
(2715 1310);
DISPLAY 0.680851 (2715 1310);
PAINT MONO (2715 1310);
FORCEPROP 0 LASTPIN (2725 2100) $PN C4
J 2
(2715 2110);
DISPLAY 0.680851 (2715 2110);
PAINT MONO (2715 2110);
FORCEPROP 0 LASTPIN (2725 -350) $PN D1
J 2
(2715 -340);
DISPLAY 0.680851 (2715 -340);
PAINT MONO (2715 -340);
FORCEPROP 0 LASTPIN (2725 450) $PN D2
J 2
(2715 460);
DISPLAY 0.680851 (2715 460);
PAINT MONO (2715 460);
FORCEPROP 0 LASTPIN (2725 1250) $PN D3
J 2
(2715 1260);
DISPLAY 0.680851 (2715 1260);
PAINT MONO (2715 1260);
FORCEPROP 0 LASTPIN (2725 2050) $PN D4
J 2
(2715 2060);
DISPLAY 0.680851 (2715 2060);
PAINT MONO (2715 2060);
FORCEPROP 0 LASTPIN (2725 -400) $PN E1
J 2
(2715 -390);
DISPLAY 0.680851 (2715 -390);
PAINT MONO (2715 -390);
FORCEPROP 0 LASTPIN (2725 400) $PN E2
J 2
(2715 410);
DISPLAY 0.680851 (2715 410);
PAINT MONO (2715 410);
FORCEPROP 0 LASTPIN (2725 1200) $PN E3
J 2
(2715 1210);
DISPLAY 0.680851 (2715 1210);
PAINT MONO (2715 1210);
FORCEPROP 0 LASTPIN (2725 2000) $PN E4
J 2
(2715 2010);
DISPLAY 0.680851 (2715 2010);
PAINT MONO (2715 2010);
FORCEPROP 0 LASTPIN (2725 -450) $PN F1
J 2
(2715 -440);
DISPLAY 0.680851 (2715 -440);
PAINT MONO (2715 -440);
FORCEPROP 0 LASTPIN (2725 350) $PN F2
J 2
(2715 360);
DISPLAY 0.680851 (2715 360);
PAINT MONO (2715 360);
FORCEPROP 0 LASTPIN (2725 1150) $PN F3
J 2
(2715 1160);
DISPLAY 0.680851 (2715 1160);
PAINT MONO (2715 1160);
FORCEPROP 0 LASTPIN (2725 1950) $PN F4
J 2
(2715 1960);
DISPLAY 0.680851 (2715 1960);
PAINT MONO (2715 1960);
FORCEPROP 0 LASTPIN (2725 -500) $PN G1
J 2
(2715 -490);
DISPLAY 0.680851 (2715 -490);
PAINT MONO (2715 -490);
FORCEPROP 0 LASTPIN (2725 300) $PN G2
J 2
(2715 310);
DISPLAY 0.680851 (2715 310);
PAINT MONO (2715 310);
FORCEPROP 0 LASTPIN (2725 1100) $PN G3
J 2
(2715 1110);
DISPLAY 0.680851 (2715 1110);
PAINT MONO (2715 1110);
FORCEPROP 0 LASTPIN (2725 1900) $PN G4
J 2
(2715 1910);
DISPLAY 0.680851 (2715 1910);
PAINT MONO (2715 1910);
FORCEPROP 0 LASTPIN (2725 -550) $PN H1
J 2
(2715 -540);
DISPLAY 0.680851 (2715 -540);
PAINT MONO (2715 -540);
FORCEPROP 0 LASTPIN (2725 250) $PN H2
J 2
(2715 260);
DISPLAY 0.680851 (2715 260);
PAINT MONO (2715 260);
FORCEPROP 0 LASTPIN (2725 1050) $PN H3
J 2
(2715 1060);
DISPLAY 0.680851 (2715 1060);
PAINT MONO (2715 1060);
FORCEPROP 0 LASTPIN (2725 1850) $PN H4
J 2
(2715 1860);
DISPLAY 0.680851 (2715 1860);
PAINT MONO (2715 1860);
FORCEPROP 0 LASTPIN (2725 -600) $PN I1
J 2
(2715 -590);
DISPLAY 0.680851 (2715 -590);
PAINT MONO (2715 -590);
FORCEPROP 0 LASTPIN (2725 200) $PN I2
J 2
(2715 210);
DISPLAY 0.680851 (2715 210);
PAINT MONO (2715 210);
FORCEPROP 0 LASTPIN (2725 1000) $PN I3
J 2
(2715 1010);
DISPLAY 0.680851 (2715 1010);
PAINT MONO (2715 1010);
FORCEPROP 0 LASTPIN (2725 1800) $PN I4
J 2
(2715 1810);
DISPLAY 0.680851 (2715 1810);
PAINT MONO (2715 1810);
FORCEPROP 0 LASTPIN (2725 -650) $PN J1
J 2
(2715 -640);
DISPLAY 0.680851 (2715 -640);
PAINT MONO (2715 -640);
FORCEPROP 0 LASTPIN (2725 150) $PN J2
J 2
(2715 160);
DISPLAY 0.680851 (2715 160);
PAINT MONO (2715 160);
FORCEPROP 0 LASTPIN (2725 950) $PN J3
J 2
(2715 960);
DISPLAY 0.680851 (2715 960);
PAINT MONO (2715 960);
FORCEPROP 0 LASTPIN (2725 1750) $PN J4
J 2
(2715 1760);
DISPLAY 0.680851 (2715 1760);
PAINT MONO (2715 1760);
FORCEPROP 0 LASTPIN (2725 -700) $PN K1
J 2
(2715 -690);
DISPLAY 0.680851 (2715 -690);
PAINT MONO (2715 -690);
FORCEPROP 0 LASTPIN (2725 100) $PN K2
J 2
(2715 110);
DISPLAY 0.680851 (2715 110);
PAINT MONO (2715 110);
FORCEPROP 0 LASTPIN (2725 900) $PN K3
J 2
(2715 910);
DISPLAY 0.680851 (2715 910);
PAINT MONO (2715 910);
FORCEPROP 0 LASTPIN (2725 1700) $PN K4
J 2
(2715 1710);
DISPLAY 0.680851 (2715 1710);
PAINT MONO (2715 1710);
FORCEPROP 0 LASTPIN (2725 -750) $PN L1
J 2
(2715 -740);
DISPLAY 0.680851 (2715 -740);
PAINT MONO (2715 -740);
FORCEPROP 0 LASTPIN (2725 50) $PN L2
J 2
(2715 60);
DISPLAY 0.680851 (2715 60);
PAINT MONO (2715 60);
FORCEPROP 0 LASTPIN (2725 850) $PN L3
J 2
(2715 860);
DISPLAY 0.680851 (2715 860);
PAINT MONO (2715 860);
FORCEPROP 0 LASTPIN (2725 1650) $PN L4
J 2
(2715 1660);
DISPLAY 0.680851 (2715 1660);
PAINT MONO (2715 1660);
FORCEPROP 0 LASTPIN (2725 -800) $PN M1
J 2
(2715 -790);
DISPLAY 0.680851 (2715 -790);
PAINT MONO (2715 -790);
FORCEPROP 0 LASTPIN (2725 0) $PN M2
J 2
(2715 10);
DISPLAY 0.680851 (2715 10);
PAINT MONO (2715 10);
FORCEPROP 0 LASTPIN (2725 800) $PN M3
J 2
(2715 810);
DISPLAY 0.680851 (2715 810);
PAINT MONO (2715 810);
FORCEPROP 0 LASTPIN (2725 1600) $PN M4
J 2
(2715 1610);
DISPLAY 0.680851 (2715 1610);
PAINT MONO (2715 1610);
FORCEPROP 0 LASTPIN (2725 -850) $PN N1
J 2
(2715 -840);
DISPLAY 0.680851 (2715 -840);
PAINT MONO (2715 -840);
FORCEPROP 0 LASTPIN (2725 -50) $PN N2
J 2
(2715 -40);
DISPLAY 0.680851 (2715 -40);
PAINT MONO (2715 -40);
FORCEPROP 0 LASTPIN (2725 750) $PN N3
J 2
(2715 760);
DISPLAY 0.680851 (2715 760);
PAINT MONO (2715 760);
FORCEPROP 0 LASTPIN (2725 1550) $PN N4
J 2
(2715 1560);
DISPLAY 0.680851 (2715 1560);
PAINT MONO (2715 1560);
FORCEPROP 2 LAST PART_TYPE THLF
J 0
(2900 2600);
DISPLAY 1.021277 (2900 2600);
FORCEPROP 1 LAST MATERIAL IO
J 0
(2908 2413);
DISPLAY 0.723404 (2908 2413);
PAINT GREEN (2908 2413);
FORCEPROP 2 LAST CDS_LIB pure_quanta
J 0
(3650 700);
DISPLAY INVISIBLE (3650 700);
FORCEPROP 1 LAST CDS_LMAN_SYM_OUTLINE -775,1650,775,-1650
J 0
(3650 700);
DISPLAY 0.468085 (3650 700);
PAINT GREEN (3650 700);
DISPLAY INVISIBLE (3650 700);
FORCEPROP 0 LAST VALUE CONN112_10137002-101LF
J 0
(2900 2600);
DISPLAY 1.021277 (2900 2600);
DISPLAY INVISIBLE (2900 2600);
FORCEPROP 1 LAST NEEDS_NO_SIZE TRUE
J 0
(3650 700);
DISPLAY 0.723404 (3650 700);
PAINT GREEN (3650 700);
DISPLAY INVISIBLE (3650 700);
FORCEPROP 1 LAST PATH I76
J 0
(3650 700);
DISPLAY 0.723404 (3650 700);
PAINT GREEN (3650 700);
DISPLAY INVISIBLE (3650 700);
FORCEPROP 1 LAST PART_NUMBER DFHSB2FR012
J 0
(2900 2475);
DISPLAY 0.723404 (2900 2475);
PAINT GREEN (2900 2475);
DISPLAY INVISIBLE (2900 2475);
FORCEADD OFFPAGE..2
R 2
(-3325 -225);
FORCEPROP 2 LAST $XR0 341 
J 0
(-3580 -225);
DISPLAY 0.638298 (-3580 -225);
PAINT MONO (-3580 -225);
FORCEPROP 2 LAST CDS_LIB standard
J 0
(-3325 -225);
DISPLAY INVISIBLE (-3325 -225);
FORCEPROP 1 LAST OFFPAGE TRUE
J 2
(-3650 -350);
DISPLAY 0.872340 (-3650 -350);
PAINT AQUA (-3650 -350);
DISPLAY INVISIBLE (-3650 -350);
FORCEPROP 1 LAST COMMENT_BODY TRUE
J 2
(-3280 -320);
DISPLAY 0.872340 (-3280 -320);
PAINT GREEN (-3280 -320);
DISPLAY INVISIBLE (-3280 -320);
FORCEPROP 2 LAST PATH I8
J 0
(-3600 -175);
DISPLAY 0.680851 (-3600 -175);
DISPLAY INVISIBLE (-3600 -175);
FORCEADD OFFPAGE..2
R 2
(-3325 25);
FORCEPROP 2 LAST $XR0 125 
J 0
(-3580 25);
DISPLAY 0.638298 (-3580 25);
PAINT MONO (-3580 25);
FORCEPROP 2 LAST CDS_LIB standard
J 0
(-3325 25);
DISPLAY INVISIBLE (-3325 25);
FORCEPROP 1 LAST OFFPAGE TRUE
J 2
(-3650 -100);
DISPLAY 0.872340 (-3650 -100);
PAINT AQUA (-3650 -100);
DISPLAY INVISIBLE (-3650 -100);
FORCEPROP 1 LAST COMMENT_BODY TRUE
J 2
(-3280 -70);
DISPLAY 0.872340 (-3280 -70);
PAINT GREEN (-3280 -70);
DISPLAY INVISIBLE (-3280 -70);
FORCEPROP 2 LAST PATH I9
J 0
(-3600 75);
DISPLAY 0.680851 (-3600 75);
DISPLAY INVISIBLE (-3600 75);
FORCEADD QUANTA_TITLE_BLOCK_C..1
(4700 -3350);
FORCEPROP 0 LAST CDS_CON_LAST_MODIFIED Thu Sep 14 16:12:58 2023
J 0
(2815 -3335);
PAINT MONO (2815 -3335);
DISPLAY INVISIBLE (2815 -3335);
FORCEPROP 2 LAST CUSTOM_TXT_CDS <XR_PAGE_TITLE>
J 0
(-3190 1900);
DISPLAY 0.638298 (-3190 1900);
PAINT PINK (-3190 1900);
DISPLAY INVISIBLE (-3190 1900);
FORCEPROP 2 LAST CUSTOM_TXT_CDS <CON_LAST_MODIFIED>
J 0
(2850 -3325);
DISPLAY 0.978723 (2850 -3325);
FORCEPROP 2 LAST CUSTOM_TXT_CDS <CON_PAGE_NUM> OF <CON_TOTAL_PAGES>
J 0
(4225 -3350);
DISPLAY 0.978723 (4225 -3350);
FORCEPROP 2 LAST CUSTOM_TXT_CDS <Q_NUMBER>
J 0
(3297 -3247);
DISPLAY 1.212766 (3297 -3247);
FORCEPROP 2 LAST CUSTOM_TXT_CDS <Q_REV>
J 0
(4516 -3247);
DISPLAY 1.212766 (4516 -3247);
FORCEPROP 2 LAST CUSTOM_TXT_CDS <NAME_2>
J 0
(1525 -3300);
FORCEPROP 2 LAST CUSTOM_TXT_CDS <NAME_1>
J 0
(1525 -3175);
FORCEPROP 2 LAST CUSTOM_TXT_CDS <Q_PROJ>
J 0
(2318 -3248);
DISPLAY 1.212766 (2318 -3248);
FORCEPROP 1 LAST Q_TITLE PCIE - CPU1_EXAMAX_P2/P3_X16
J 0
(-4575 -3300);
DISPLAY 1.957447 (-4575 -3300);
PAINT GREEN (-4575 -3300);
FORCEPROP 2 LAST PAGE_BORDER TRUE
J 0
(-3190 1900);
DISPLAY 0.638298 (-3190 1900);
PAINT PINK (-3190 1900);
DISPLAY INVISIBLE (-3190 1900);
FORCEPROP 2 LAST CDS_LIB pure_quanta
J 0
(4700 -3350);
PAINT MONO (4700 -3350);
DISPLAY INVISIBLE (4700 -3350);
FORCEPROP 1 LAST CDS_LMAN_SYM_OUTLINE -9475,6775,100,-125
J 0
(4700 -3350);
DISPLAY 0.468085 (4700 -3350);
PAINT GREEN (4700 -3350);
DISPLAY INVISIBLE (4700 -3350);
FORCEPROP 2 LAST CDS_XR_PAGE_TITLE CR-119 : @T6G_MB_LIB.T6G(SCH_1):PAGE119
J 0
(-3190 1900);
DISPLAY 0.638298 (-3190 1900);
PAINT PINK (-3190 1900);
DISPLAY INVISIBLE (-3190 1900);
FORCEPROP 1 LAST Q_DEPT BU9
J 1
(937 -3301);
DISPLAY 1.957447 (937 -3301);
PAINT GREEN (937 -3301);
DISPLAY INVISIBLE (937 -3301);
FORCEPROP 1 LAST COMMENT_BODY TRUE
J 0
(4712 -3363);
DISPLAY 0.978723 (4712 -3363);
PAINT GREEN (4712 -3363);
DISPLAY INVISIBLE (4712 -3363);
WIRE 16 -1 (-2050 1625)(-3275 1625);
FORCEPROP 2 LAST SIG_NAME PRSNT_CABLE_GPU_B3_N
J 0
(-3110 1635);
DISPLAY 0.638298 (-3110 1635);
WIRE 16 -1 (-2050 2225)(-3275 2225);
FORCEPROP 2 LAST SIG_NAME P5E_CPU1_P2_RX_BUF_DN<15>
J 0
(-3110 2235);
DISPLAY 0.638298 (-3110 2235);
WIRE 16 -1 (-2050 2175)(-3275 2175);
FORCEPROP 2 LAST SIG_NAME P5E_CPU1_P2_RX_BUF_DP<15>
J 0
(-3110 2185);
DISPLAY 0.638298 (-3110 2185);
WIRE 16 -1 (-2050 1725)(-3275 1725);
FORCEPROP 2 LAST SIG_NAME P5E_CPU1_P3_TX_BUF_C_DP<15>
J 0
(-3110 1735);
DISPLAY 0.638298 (-3110 1735);
WIRE 16 -1 (-2050 1775)(-3275 1775);
FORCEPROP 2 LAST SIG_NAME P5E_CPU1_P3_TX_BUF_C_DN<15>
J 0
(-3110 1785);
DISPLAY 0.638298 (-3110 1785);
WIRE 16 -1 (-2050 1875)(-3275 1875);
FORCEPROP 2 LAST SIG_NAME P5E_CPU1_P2_TX_BUF_C_DP<15>
J 0
(-3110 1885);
DISPLAY 0.638298 (-3110 1885);
WIRE 16 -1 (-2050 1925)(-3275 1925);
FORCEPROP 2 LAST SIG_NAME P5E_CPU1_P2_TX_BUF_C_DN<15>
J 0
(-3110 1935);
DISPLAY 0.638298 (-3110 1935);
WIRE 16 -1 (-2050 1475)(-3275 1475);
FORCEPROP 2 LAST SIG_NAME SMB_BMC_SWB_BUF_SDA
J 0
(-3110 1485);
DISPLAY 0.638298 (-3110 1485);
WIRE 16 -1 (-2050 1325)(-3275 1325);
FORCEPROP 2 LAST SIG_NAME P5E_CPU1_P2_RX_BUF_DP<14>
J 0
(-3110 1335);
DISPLAY 0.638298 (-3110 1335);
WIRE 16 -1 (-2050 875)(-3275 875);
FORCEPROP 2 LAST SIG_NAME P5E_CPU1_P3_TX_BUF_C_DP<14>
J 0
(-3110 885);
DISPLAY 0.638298 (-3110 885);
WIRE 16 -1 (-2050 475)(-3275 475);
FORCEPROP 2 LAST SIG_NAME P5E_CPU1_P3_RX_BUF_DN<13>
J 0
(-3110 485);
DISPLAY 0.638298 (-3110 485);
WIRE 16 -1 (2725 -750)(1500 -750);
FORCEPROP 2 LAST SIG_NAME P5E_CPU1_P3_TX_BUF_C_DN<8>
J 0
(1640 -740);
DISPLAY 0.638298 (1640 -740);
WIRE 16 -1 (2725 -800)(1500 -800);
FORCEPROP 2 LAST SIG_NAME P5E_CPU1_P3_TX_BUF_C_DP<8>
J 0
(1640 -790);
DISPLAY 0.638298 (1640 -790);
WIRE 16 -1 (2725 2200)(2500 2200);
WIRE 16 -1 (2500 2200)(2500 2050);
WIRE 16 -1 (2725 2050)(2500 2050);
WIRE 16 -1 (2500 2050)(2500 1900);
WIRE 16 -1 (2725 1900)(2500 1900);
WIRE 16 -1 (2500 1900)(2500 1750);
WIRE 16 -1 (2725 1750)(2500 1750);
WIRE 16 -1 (2500 1750)(2500 1600);
WIRE 16 -1 (2725 1600)(2500 1600);
WIRE 16 -1 (2500 1600)(2500 1350);
WIRE 16 -1 (2725 1350)(2500 1350);
WIRE 16 -1 (2500 1350)(2500 1200);
WIRE 16 -1 (2725 1200)(2500 1200);
WIRE 16 -1 (2500 1200)(2500 1050);
WIRE 16 -1 (2725 1050)(2500 1050);
WIRE 16 -1 (2500 1050)(2500 900);
WIRE 16 -1 (2725 900)(2500 900);
WIRE 16 -1 (2500 900)(2500 750);
WIRE 16 -1 (2725 750)(2500 750);
WIRE 16 -1 (2500 750)(2500 600);
WIRE 16 -1 (2725 600)(2500 600);
WIRE 16 -1 (2500 600)(2500 450);
WIRE 16 -1 (2725 450)(2500 450);
WIRE 16 -1 (2500 450)(2500 300);
WIRE 16 -1 (2725 300)(2500 300);
WIRE 16 -1 (2500 300)(2500 150);
WIRE 16 -1 (2725 150)(2500 150);
WIRE 16 -1 (2500 150)(2500 0);
WIRE 16 -1 (2725 0)(2500 0);
WIRE 16 -1 (2500 0)(2500 -250);
WIRE 16 -1 (2725 -250)(2500 -250);
WIRE 16 -1 (2500 -250)(2500 -400);
WIRE 16 -1 (2725 -400)(2500 -400);
WIRE 16 -1 (2500 -400)(2500 -550);
WIRE 16 -1 (2725 -550)(2500 -550);
WIRE 16 -1 (2500 -550)(2500 -700);
WIRE 16 -1 (2725 -700)(2500 -700);
WIRE 16 -1 (2500 -700)(2500 -850);
WIRE 16 -1 (2725 -850)(2500 -850);
WIRE 16 -1 (2500 -850)(2500 -1200);
WIRE 16 -1 (2725 -650)(1500 -650);
FORCEPROP 2 LAST SIG_NAME P5E_CPU1_P2_TX_BUF_C_DP<8>
J 0
(1640 -640);
DISPLAY 0.638298 (1640 -640);
WIRE 16 -1 (2725 -500)(1500 -500);
FORCEPROP 2 LAST SIG_NAME P5E_CPU1_P3_RX_BUF_DP<8>
J 0
(1640 -490);
DISPLAY 0.638298 (1640 -490);
WIRE 16 -1 (2725 -450)(1500 -450);
FORCEPROP 2 LAST SIG_NAME P5E_CPU1_P3_RX_BUF_DN<8>
J 0
(1640 -440);
DISPLAY 0.638298 (1640 -440);
WIRE 16 -1 (2725 -350)(1500 -350);
FORCEPROP 2 LAST SIG_NAME P5E_CPU1_P2_RX_BUF_DP<8>
J 0
(1640 -340);
DISPLAY 0.638298 (1640 -340);
WIRE 16 -1 (2725 -200)(1500 -200);
FORCEPROP 2 LAST SIG_NAME BMC_MONITER_BUF
J 0
(1640 -190);
DISPLAY 0.638298 (1640 -190);
WIRE 16 -1 (2725 50)(1500 50);
FORCEPROP 2 LAST SIG_NAME P5E_CPU1_P3_TX_BUF_C_DP<9>
J 0
(1640 60);
DISPLAY 0.638298 (1640 60);
WIRE 16 -1 (2725 -50)(1500 -50);
FORCEPROP 2 LAST SIG_NAME GPU_FPGA_EROT_FATALERR_N
J 0
(1640 -40);
DISPLAY 0.638298 (1640 -40);
WIRE 16 -1 (2725 -300)(1500 -300);
FORCEPROP 2 LAST SIG_NAME P5E_CPU1_P2_RX_BUF_DN<8>
J 0
(1640 -290);
DISPLAY 0.638298 (1640 -290);
WIRE 16 -1 (2725 100)(1500 100);
FORCEPROP 2 LAST SIG_NAME P5E_CPU1_P3_TX_BUF_C_DN<9>
J 0
(1640 110);
DISPLAY 0.638298 (1640 110);
WIRE 16 -1 (2725 200)(1500 200);
FORCEPROP 2 LAST SIG_NAME P5E_CPU1_P2_TX_BUF_C_DP<9>
J 0
(1640 210);
DISPLAY 0.638298 (1640 210);
WIRE 16 -1 (2725 250)(1500 250);
FORCEPROP 2 LAST SIG_NAME P5E_CPU1_P2_TX_BUF_C_DN<9>
J 0
(1640 260);
DISPLAY 0.638298 (1640 260);
WIRE 16 -1 (2725 500)(1500 500);
FORCEPROP 2 LAST SIG_NAME P5E_CPU1_P2_RX_BUF_DP<9>
J 0
(1640 510);
DISPLAY 0.638298 (1640 510);
WIRE 16 -1 (2725 800)(1475 800);
FORCEPROP 2 LAST SIG_NAME P5E_CPU1_P3_TX_BUF_C_DP<10>
J 0
(1640 810);
DISPLAY 0.638298 (1640 810);
WIRE 16 -1 (2725 850)(1475 850);
FORCEPROP 2 LAST SIG_NAME P5E_CPU1_P3_TX_BUF_C_DN<10>
J 0
(1640 860);
DISPLAY 0.638298 (1640 860);
WIRE 16 -1 (2725 550)(1500 550);
FORCEPROP 2 LAST SIG_NAME P5E_CPU1_P2_RX_BUF_DN<9>
J 0
(1640 560);
DISPLAY 0.638298 (1640 560);
WIRE 16 -1 (2725 950)(1475 950);
FORCEPROP 2 LAST SIG_NAME P5E_CPU1_P2_TX_BUF_C_DP<10>
J 0
(1640 960);
DISPLAY 0.638298 (1640 960);
WIRE 16 -1 (2725 1100)(1475 1100);
FORCEPROP 2 LAST SIG_NAME P5E_CPU1_P3_RX_BUF_DP<10>
J 0
(1640 1110);
DISPLAY 0.638298 (1640 1110);
WIRE 16 -1 (2725 1250)(1475 1250);
FORCEPROP 2 LAST SIG_NAME P5E_CPU1_P2_RX_BUF_DP<10>
J 0
(1640 1260);
DISPLAY 0.638298 (1640 1260);
WIRE 16 -1 (2725 1400)(1475 1400);
FORCEPROP 2 LAST SIG_NAME BIC_MONITER
J 0
(1640 1410);
DISPLAY 0.638298 (1640 1410);
WIRE 16 -1 (2725 1550)(1500 1550);
FORCEPROP 2 LAST SIG_NAME GPU_3V3IO_RSVD0_FFU
J 0
(1640 1560);
DISPLAY 0.638298 (1640 1560);
WIRE 16 -1 (2725 1650)(1475 1650);
FORCEPROP 2 LAST SIG_NAME P5E_CPU1_P3_TX_BUF_C_DP<11>
J 0
(1640 1660);
DISPLAY 0.638298 (1640 1660);
WIRE 16 -1 (2725 1700)(1475 1700);
FORCEPROP 2 LAST SIG_NAME P5E_CPU1_P3_TX_BUF_C_DN<11>
J 0
(1640 1710);
DISPLAY 0.638298 (1640 1710);
WIRE 16 -1 (2725 1800)(1475 1800);
FORCEPROP 2 LAST SIG_NAME P5E_CPU1_P2_TX_BUF_C_DP<11>
J 0
(1640 1810);
DISPLAY 0.638298 (1640 1810);
WIRE 16 -1 (2725 1850)(1475 1850);
FORCEPROP 2 LAST SIG_NAME P5E_CPU1_P2_TX_BUF_C_DN<11>
J 0
(1640 1860);
DISPLAY 0.638298 (1640 1860);
WIRE 16 -1 (2725 1950)(1475 1950);
FORCEPROP 2 LAST SIG_NAME P5E_CPU1_P3_RX_BUF_DP<11>
J 0
(1640 1960);
DISPLAY 0.638298 (1640 1960);
WIRE 16 -1 (2725 2000)(1475 2000);
FORCEPROP 2 LAST SIG_NAME P5E_CPU1_P3_RX_BUF_DN<11>
J 0
(1640 2010);
DISPLAY 0.638298 (1640 2010);
WIRE 16 -1 (2725 2100)(1475 2100);
FORCEPROP 2 LAST SIG_NAME P5E_CPU1_P2_RX_BUF_DP<11>
J 0
(1640 2110);
DISPLAY 0.638298 (1640 2110);
WIRE 16 -1 (2725 2150)(1475 2150);
FORCEPROP 2 LAST SIG_NAME P5E_CPU1_P2_RX_BUF_DN<11>
J 0
(1640 2160);
DISPLAY 0.638298 (1640 2160);
WIRE 16 -1 (-2050 -125)(-3275 -125);
FORCEPROP 2 LAST SIG_NAME SMB_BMC_SWB_BUF_SCL
J 0
(-3110 -115);
DISPLAY 0.638298 (-3110 -115);
WIRE 16 -1 (-2050 2275)(-2225 2275);
WIRE 16 -1 (-2225 2275)(-2225 2125);
WIRE 16 -1 (-2050 2125)(-2225 2125);
WIRE 16 -1 (-2225 2125)(-2225 1975);
WIRE 16 -1 (-2050 1975)(-2225 1975);
WIRE 16 -1 (-2225 1975)(-2225 1825);
WIRE 16 -1 (-2050 1825)(-2225 1825);
WIRE 16 -1 (-2225 1825)(-2225 1675);
WIRE 16 -1 (-2050 1675)(-2225 1675);
WIRE 16 -1 (-2225 1675)(-2225 1425);
WIRE 16 -1 (-2050 1425)(-2225 1425);
WIRE 16 -1 (-2225 1425)(-2225 1275);
WIRE 16 -1 (-2050 1275)(-2225 1275);
WIRE 16 -1 (-2225 1275)(-2225 1125);
WIRE 16 -1 (-2050 1125)(-2225 1125);
WIRE 16 -1 (-2225 1125)(-2225 975);
WIRE 16 -1 (-2050 975)(-2225 975);
WIRE 16 -1 (-2225 975)(-2225 825);
WIRE 16 -1 (-2050 825)(-2225 825);
WIRE 16 -1 (-2225 825)(-2225 675);
WIRE 16 -1 (-2050 675)(-2225 675);
WIRE 16 -1 (-2225 675)(-2225 525);
WIRE 16 -1 (-2050 525)(-2225 525);
WIRE 16 -1 (-2225 525)(-2225 375);
WIRE 16 -1 (-2050 375)(-2225 375);
WIRE 16 -1 (-2225 375)(-2225 225);
WIRE 16 -1 (-2050 225)(-2225 225);
WIRE 16 -1 (-2225 225)(-2225 75);
WIRE 16 -1 (-2050 75)(-2225 75);
WIRE 16 -1 (-2225 75)(-2225 -175);
WIRE 16 -1 (-2050 -175)(-2225 -175);
WIRE 16 -1 (-2225 -325)(-2225 -175);
WIRE 16 -1 (-2050 -325)(-2225 -325);
WIRE 16 -1 (-2225 -475)(-2225 -325);
WIRE 16 -1 (-2050 -475)(-2225 -475);
WIRE 16 -1 (-2225 -475)(-2225 -625);
WIRE 16 -1 (-2050 -625)(-2225 -625);
WIRE 16 -1 (-2225 -625)(-2225 -775);
WIRE 16 -1 (-2050 -775)(-2225 -775);
WIRE 16 -1 (-2225 -775)(-2225 -1075);
WIRE 16 -1 (-2050 -225)(-3275 -225);
FORCEPROP 2 LAST SIG_NAME P5E_CPU1_P2_RX_BUF_DN<12>
J 0
(-3110 -215);
DISPLAY 0.638298 (-3110 -215);
WIRE 16 -1 (-2050 -275)(-3275 -275);
FORCEPROP 2 LAST SIG_NAME P5E_CPU1_P2_RX_BUF_DP<12>
J 0
(-3110 -265);
DISPLAY 0.638298 (-3110 -265);
WIRE 16 -1 (-2050 25)(-3275 25);
FORCEPROP 2 LAST SIG_NAME GPU_3V3IO_RSVD1_FFU
J 0
(-3110 35);
DISPLAY 0.638298 (-3110 35);
WIRE 16 -1 (-2050 175)(-3275 175);
FORCEPROP 2 LAST SIG_NAME P5E_CPU1_P3_TX_BUF_C_DN<13>
J 0
(-3110 185);
DISPLAY 0.638298 (-3110 185);
WIRE 16 -1 (-2050 125)(-3275 125);
FORCEPROP 2 LAST SIG_NAME P5E_CPU1_P3_TX_BUF_C_DP<13>
J 0
(-3110 135);
DISPLAY 0.638298 (-3110 135);
WIRE 16 -1 (-2050 -425)(-3275 -425);
FORCEPROP 2 LAST SIG_NAME P5E_CPU1_P3_RX_BUF_DP<12>
J 0
(-3110 -415);
DISPLAY 0.638298 (-3110 -415);
WIRE 16 -1 (-2050 -525)(-3275 -525);
FORCEPROP 2 LAST SIG_NAME P5E_CPU1_P2_TX_BUF_C_DN<12>
J 0
(-3110 -515);
DISPLAY 0.638298 (-3110 -515);
WIRE 16 -1 (-2050 -575)(-3275 -575);
FORCEPROP 2 LAST SIG_NAME P5E_CPU1_P2_TX_BUF_C_DP<12>
J 0
(-3110 -565);
DISPLAY 0.638298 (-3110 -565);
WIRE 16 -1 (-2050 -725)(-3275 -725);
FORCEPROP 2 LAST SIG_NAME P5E_CPU1_P3_TX_BUF_C_DP<12>
J 0
(-3110 -715);
DISPLAY 0.638298 (-3110 -715);
WIRE 16 -1 (-2050 -375)(-3275 -375);
FORCEPROP 2 LAST SIG_NAME P5E_CPU1_P3_RX_BUF_DN<12>
J 0
(-3110 -365);
DISPLAY 0.638298 (-3110 -365);
WIRE 16 -1 (-2050 275)(-3275 275);
FORCEPROP 2 LAST SIG_NAME P5E_CPU1_P2_TX_BUF_C_DP<13>
J 0
(-3110 285);
DISPLAY 0.638298 (-3110 285);
WIRE 16 -1 (-2050 325)(-3275 325);
FORCEPROP 2 LAST SIG_NAME P5E_CPU1_P2_TX_BUF_C_DN<13>
J 0
(-3110 335);
DISPLAY 0.638298 (-3110 335);
WIRE 16 -1 (-2050 425)(-3275 425);
FORCEPROP 2 LAST SIG_NAME P5E_CPU1_P3_RX_BUF_DP<13>
J 0
(-3110 435);
DISPLAY 0.638298 (-3110 435);
WIRE 16 -1 (-2050 575)(-3275 575);
FORCEPROP 2 LAST SIG_NAME P5E_CPU1_P2_RX_BUF_DP<13>
J 0
(-3110 585);
DISPLAY 0.638298 (-3110 585);
WIRE 16 -1 (-2050 925)(-3275 925);
FORCEPROP 2 LAST SIG_NAME P5E_CPU1_P3_TX_BUF_C_DN<14>
J 0
(-3110 935);
DISPLAY 0.638298 (-3110 935);
WIRE 16 -1 (-2050 1025)(-3275 1025);
FORCEPROP 2 LAST SIG_NAME P5E_CPU1_P2_TX_BUF_C_DP<14>
J 0
(-3110 1035);
DISPLAY 0.638298 (-3110 1035);
WIRE 16 -1 (-2050 1075)(-3275 1075);
FORCEPROP 2 LAST SIG_NAME P5E_CPU1_P2_TX_BUF_C_DN<14>
J 0
(-3110 1085);
DISPLAY 0.638298 (-3110 1085);
WIRE 16 -1 (-2050 1175)(-3275 1175);
FORCEPROP 2 LAST SIG_NAME P5E_CPU1_P3_RX_BUF_DP<14>
J 0
(-3110 1185);
DISPLAY 0.638298 (-3110 1185);
WIRE 16 -1 (-2050 1225)(-3275 1225);
FORCEPROP 2 LAST SIG_NAME P5E_CPU1_P3_RX_BUF_DN<14>
J 0
(-3110 1235);
DISPLAY 0.638298 (-3110 1235);
WIRE 16 -1 (-2050 -675)(-3275 -675);
FORCEPROP 2 LAST SIG_NAME P5E_CPU1_P3_TX_BUF_C_DN<12>
J 0
(-3110 -665);
DISPLAY 0.638298 (-3110 -665);
WIRE 16 -1 (-2050 625)(-3275 625);
FORCEPROP 2 LAST SIG_NAME P5E_CPU1_P2_RX_BUF_DN<13>
J 0
(-3110 635);
DISPLAY 0.638298 (-3110 635);
WIRE 16 -1 (-2050 2025)(-3275 2025);
FORCEPROP 2 LAST SIG_NAME P5E_CPU1_P3_RX_BUF_DP<15>
J 0
(-3110 2035);
DISPLAY 0.638298 (-3110 2035);
WIRE 16 -1 (-2050 1375)(-3275 1375);
FORCEPROP 2 LAST SIG_NAME P5E_CPU1_P2_RX_BUF_DN<14>
J 0
(-3110 1385);
DISPLAY 0.638298 (-3110 1385);
WIRE 16 -1 (2725 -600)(1500 -600);
FORCEPROP 2 LAST SIG_NAME P5E_CPU1_P2_TX_BUF_C_DN<8>
J 0
(1640 -590);
DISPLAY 0.638298 (1640 -590);
WIRE 16 -1 (2725 350)(1500 350);
FORCEPROP 2 LAST SIG_NAME P5E_CPU1_P3_RX_BUF_DP<9>
J 0
(1640 360);
DISPLAY 0.638298 (1640 360);
WIRE 16 -1 (2725 1150)(1475 1150);
FORCEPROP 2 LAST SIG_NAME P5E_CPU1_P3_RX_BUF_DN<10>
J 0
(1640 1160);
DISPLAY 0.638298 (1640 1160);
WIRE 16 -1 (-2050 2075)(-3275 2075);
FORCEPROP 2 LAST SIG_NAME P5E_CPU1_P3_RX_BUF_DN<15>
J 0
(-3110 2085);
DISPLAY 0.638298 (-3110 2085);
WIRE 16 -1 (2725 1000)(1475 1000);
FORCEPROP 2 LAST SIG_NAME P5E_CPU1_P2_TX_BUF_C_DN<10>
J 0
(1640 1010);
DISPLAY 0.638298 (1640 1010);
WIRE 16 -1 (2725 1300)(1475 1300);
FORCEPROP 2 LAST SIG_NAME P5E_CPU1_P2_RX_BUF_DN<10>
J 0
(1640 1310);
DISPLAY 0.638298 (1640 1310);
WIRE 16 -1 (2725 400)(1500 400);
FORCEPROP 2 LAST SIG_NAME P5E_CPU1_P3_RX_BUF_DN<9>
J 0
(1640 410);
DISPLAY 0.638298 (1640 410);
DOT 1 (2500 -850);
DOT 1 (-2225 75);
DOT 1 (-2225 525);
DOT 1 (-2225 975);
DOT 1 (2500 2050);
DOT 1 (2500 1900);
DOT 1 (2500 1750);
DOT 1 (2500 1600);
DOT 1 (2500 1200);
DOT 1 (2500 900);
DOT 1 (2500 1050);
DOT 1 (2500 750);
DOT 1 (2500 600);
DOT 1 (2500 450);
DOT 1 (2500 300);
DOT 1 (2500 150);
DOT 1 (2500 0);
DOT 1 (2500 -400);
DOT 1 (2500 -550);
DOT 1 (2500 -700);
DOT 1 (-2225 1975);
DOT 1 (-2225 2125);
DOT 1 (-2225 1825);
DOT 1 (-2225 1675);
DOT 1 (-2225 1125);
DOT 1 (-2225 675);
DOT 1 (-2225 375);
DOT 1 (-2225 225);
DOT 1 (-2225 -325);
DOT 1 (-2225 -475);
DOT 1 (-2225 -625);
DOT 1 (-2225 -775);
DOT 1 (-2225 1275);
DOT 1 (-2225 1425);
DOT 1 (-2225 825);
DOT 1 (-2225 -175);
DOT 1 (2500 1350);
DOT 1 (2500 -250);
FORCENOTE
CPU1_P3_TX/RX<0-15> LANE REVERSAL
(-4500 2600) 0;
DISPLAY LEFT (-4500 2600);
DISPLAY 1.595745 (-4500 2600);
PAINT PINK (-4500 2600);
FORCENOTE
CPU1_P2_TX/RX<0-15> LANE REVERSAL
(-4500 2700) 0;
DISPLAY LEFT (-4500 2700);
DISPLAY 1.595745 (-4500 2700);
PAINT PINK (-4500 2700);
QUIT
